FILE_TYPE = MACRO_DRAWING;
SET COLOR_WIRE YELLOW;
SET COLOR_PROP ORANGE;
SET COLOR_DOT WHITE;
SET COLOR_ARC YELLOW;
SET COLOR_BODY GREEN;
SET COLOR_NOTE PURPLE;
SET PROP_DISPLAY VALUE;
SET PAGE_NUMBER P92;
FORCEADD OFFPAGE..5
(-8325 1950);
FORCEPROP 2 LAST $XR0 17 
J 0
(-8549 1950);
DISPLAY 0.638298 (-8549 1950);
PAINT MONO (-8549 1950);
FORCEPROP 2 LAST CDS_LIB mstr_standard
J 0
(-8325 1950);
DISPLAY 0.808511 (-8325 1950);
DISPLAY INVISIBLE (-8325 1950);
FORCEPROP 1 LAST OFFPAGE TRUE
J 0
(-8000 1825);
DISPLAY 0.872340 (-8000 1825);
PAINT GREEN (-8000 1825);
DISPLAY INVISIBLE (-8000 1825);
FORCEPROP 1 LAST COMMENT_BODY TRUE
J 0
(-8225 1875);
DISPLAY 0.872340 (-8225 1875);
PAINT GREEN (-8225 1875);
DISPLAY INVISIBLE (-8225 1875);
FORCEPROP 2 LAST PATH I1
J 0
(-8275 2025);
DISPLAY 1.021277 (-8275 2025);
DISPLAY INVISIBLE (-8275 2025);
FORCEADD OFFPAGE..6
(-8325 3550);
FORCEPROP 2 LAST $XR0 17 
J 0
(-8574 3550);
DISPLAY 0.638298 (-8574 3550);
PAINT MONO (-8574 3550);
FORCEPROP 2 LAST CDS_LIB mstr_standard
J 0
(-8325 3550);
DISPLAY 0.723404 (-8325 3550);
PAINT MONO (-8325 3550);
DISPLAY INVISIBLE (-8325 3550);
FORCEPROP 1 LAST OFFPAGE TRUE
J 0
(-8000 3425);
DISPLAY 0.872340 (-8000 3425);
PAINT GREEN (-8000 3425);
DISPLAY INVISIBLE (-8000 3425);
FORCEPROP 1 LAST COMMENT_BODY TRUE
J 0
(-8225 3475);
DISPLAY 0.872340 (-8225 3475);
PAINT GREEN (-8225 3475);
DISPLAY INVISIBLE (-8225 3475);
FORCEPROP 2 LAST PATH I10
J 0
(-8275 3625);
DISPLAY 1.021277 (-8275 3625);
DISPLAY INVISIBLE (-8275 3625);
FORCEADD TAP..1
(-6025 4150);
FORCEPROP 3 LASTPIN (-6075 4150) SIG_NAME M_H_CPU0_SA_DQ<7>
J 0
(-6065 4160);
DISPLAY 0.659574 (-6065 4160);
PAINT MONO (-6065 4160);
DISPLAY INVISIBLE (-6065 4160);
FORCEPROP 1 LASTPIN (-6075 4150) BN 7
J 0
(-6087 4158);
DISPLAY 0.489362 (-6087 4158);
PAINT GREEN (-6087 4158);
FORCEPROP 2 LAST CDS_LIB mstr_standard
J 0
(-6025 4150);
DISPLAY 0.723404 (-6025 4150);
PAINT MONO (-6025 4150);
DISPLAY INVISIBLE (-6025 4150);
FORCEPROP 1 LAST BODY_TYPE PLUMBING
J 0
(-6025 4200);
DISPLAY 0.872340 (-6025 4200);
PAINT GREEN (-6025 4200);
DISPLAY INVISIBLE (-6025 4200);
FORCEPROP 1 LAST HDL_TAP TRUE
J 0
(-5700 4025);
DISPLAY 0.872340 (-5700 4025);
DISPLAY INVISIBLE (-5700 4025);
FORCEPROP 1 LAST PATH I100
J 0
(-6027 4150);
DISPLAY 0.872340 (-6027 4150);
PAINT GREEN (-6027 4150);
DISPLAY INVISIBLE (-6027 4150);
FORCEADD TAP..1
(-6025 4100);
FORCEPROP 3 LASTPIN (-6075 4100) SIG_NAME M_H_CPU0_SA_DQ<6>
J 0
(-6065 4110);
DISPLAY 0.659574 (-6065 4110);
PAINT MONO (-6065 4110);
DISPLAY INVISIBLE (-6065 4110);
FORCEPROP 1 LASTPIN (-6075 4100) BN 6
J 0
(-6087 4108);
DISPLAY 0.489362 (-6087 4108);
PAINT GREEN (-6087 4108);
FORCEPROP 2 LAST CDS_LIB mstr_standard
J 0
(-6025 4100);
DISPLAY 0.723404 (-6025 4100);
PAINT MONO (-6025 4100);
DISPLAY INVISIBLE (-6025 4100);
FORCEPROP 1 LAST BODY_TYPE PLUMBING
J 0
(-6025 4150);
DISPLAY 0.872340 (-6025 4150);
PAINT GREEN (-6025 4150);
DISPLAY INVISIBLE (-6025 4150);
FORCEPROP 1 LAST HDL_TAP TRUE
J 0
(-5700 3975);
DISPLAY 0.872340 (-5700 3975);
DISPLAY INVISIBLE (-5700 3975);
FORCEPROP 1 LAST PATH I101
J 0
(-6027 4100);
DISPLAY 0.872340 (-6027 4100);
PAINT GREEN (-6027 4100);
DISPLAY INVISIBLE (-6027 4100);
FORCEADD TAP..1
(-6025 4200);
FORCEPROP 3 LASTPIN (-6075 4200) SIG_NAME M_H_CPU0_SA_DQ<8>
J 0
(-6065 4210);
DISPLAY 0.659574 (-6065 4210);
PAINT MONO (-6065 4210);
DISPLAY INVISIBLE (-6065 4210);
FORCEPROP 1 LASTPIN (-6075 4200) BN 8
J 0
(-6087 4208);
DISPLAY 0.489362 (-6087 4208);
PAINT GREEN (-6087 4208);
FORCEPROP 2 LAST CDS_LIB mstr_standard
J 0
(-6025 4200);
DISPLAY 0.723404 (-6025 4200);
PAINT MONO (-6025 4200);
DISPLAY INVISIBLE (-6025 4200);
FORCEPROP 1 LAST BODY_TYPE PLUMBING
J 0
(-6025 4250);
DISPLAY 0.872340 (-6025 4250);
PAINT GREEN (-6025 4250);
DISPLAY INVISIBLE (-6025 4250);
FORCEPROP 1 LAST HDL_TAP TRUE
J 0
(-5700 4075);
DISPLAY 0.872340 (-5700 4075);
DISPLAY INVISIBLE (-5700 4075);
FORCEPROP 1 LAST PATH I102
J 0
(-6027 4200);
DISPLAY 0.872340 (-6027 4200);
PAINT GREEN (-6027 4200);
DISPLAY INVISIBLE (-6027 4200);
FORCEADD TAP..1
(-6025 4250);
FORCEPROP 3 LASTPIN (-6075 4250) SIG_NAME M_H_CPU0_SA_DQ<9>
J 0
(-6065 4260);
DISPLAY 0.659574 (-6065 4260);
PAINT MONO (-6065 4260);
DISPLAY INVISIBLE (-6065 4260);
FORCEPROP 1 LASTPIN (-6075 4250) BN 9
J 0
(-6087 4258);
DISPLAY 0.489362 (-6087 4258);
PAINT GREEN (-6087 4258);
FORCEPROP 2 LAST CDS_LIB mstr_standard
J 0
(-6025 4250);
DISPLAY 0.723404 (-6025 4250);
PAINT MONO (-6025 4250);
DISPLAY INVISIBLE (-6025 4250);
FORCEPROP 1 LAST BODY_TYPE PLUMBING
J 0
(-6025 4300);
DISPLAY 0.872340 (-6025 4300);
PAINT GREEN (-6025 4300);
DISPLAY INVISIBLE (-6025 4300);
FORCEPROP 1 LAST HDL_TAP TRUE
J 0
(-5700 4125);
DISPLAY 0.872340 (-5700 4125);
DISPLAY INVISIBLE (-5700 4125);
FORCEPROP 1 LAST PATH I103
J 0
(-6027 4250);
DISPLAY 0.872340 (-6027 4250);
PAINT GREEN (-6027 4250);
DISPLAY INVISIBLE (-6027 4250);
FORCEADD TAP..1
(-6025 4350);
FORCEPROP 3 LASTPIN (-6075 4350) SIG_NAME M_H_CPU0_SA_DQ<11>
J 0
(-6065 4360);
DISPLAY 0.659574 (-6065 4360);
PAINT MONO (-6065 4360);
DISPLAY INVISIBLE (-6065 4360);
FORCEPROP 1 LASTPIN (-6075 4350) BN 11
J 0
(-6087 4358);
DISPLAY 0.489362 (-6087 4358);
PAINT GREEN (-6087 4358);
FORCEPROP 2 LAST CDS_LIB mstr_standard
J 0
(-6025 4350);
DISPLAY 0.723404 (-6025 4350);
PAINT MONO (-6025 4350);
DISPLAY INVISIBLE (-6025 4350);
FORCEPROP 1 LAST BODY_TYPE PLUMBING
J 0
(-6025 4400);
DISPLAY 0.872340 (-6025 4400);
PAINT GREEN (-6025 4400);
DISPLAY INVISIBLE (-6025 4400);
FORCEPROP 1 LAST HDL_TAP TRUE
J 0
(-5700 4225);
DISPLAY 0.872340 (-5700 4225);
DISPLAY INVISIBLE (-5700 4225);
FORCEPROP 1 LAST PATH I104
J 0
(-6027 4350);
DISPLAY 0.872340 (-6027 4350);
PAINT GREEN (-6027 4350);
DISPLAY INVISIBLE (-6027 4350);
FORCEADD TAP..1
(-6025 4400);
FORCEPROP 3 LASTPIN (-6075 4400) SIG_NAME M_H_CPU0_SA_DQ<12>
J 0
(-6065 4410);
DISPLAY 0.659574 (-6065 4410);
PAINT MONO (-6065 4410);
DISPLAY INVISIBLE (-6065 4410);
FORCEPROP 1 LASTPIN (-6075 4400) BN 12
J 0
(-6087 4408);
DISPLAY 0.489362 (-6087 4408);
PAINT GREEN (-6087 4408);
FORCEPROP 2 LAST CDS_LIB mstr_standard
J 0
(-6025 4400);
DISPLAY 0.723404 (-6025 4400);
PAINT MONO (-6025 4400);
DISPLAY INVISIBLE (-6025 4400);
FORCEPROP 1 LAST BODY_TYPE PLUMBING
J 0
(-6025 4450);
DISPLAY 0.872340 (-6025 4450);
PAINT GREEN (-6025 4450);
DISPLAY INVISIBLE (-6025 4450);
FORCEPROP 1 LAST HDL_TAP TRUE
J 0
(-5700 4275);
DISPLAY 0.872340 (-5700 4275);
DISPLAY INVISIBLE (-5700 4275);
FORCEPROP 1 LAST PATH I105
J 0
(-6027 4400);
DISPLAY 0.872340 (-6027 4400);
PAINT GREEN (-6027 4400);
DISPLAY INVISIBLE (-6027 4400);
FORCEADD TAP..1
(-6025 4450);
FORCEPROP 3 LASTPIN (-6075 4450) SIG_NAME M_H_CPU0_SA_DQ<13>
J 0
(-6065 4460);
DISPLAY 0.659574 (-6065 4460);
PAINT MONO (-6065 4460);
DISPLAY INVISIBLE (-6065 4460);
FORCEPROP 1 LASTPIN (-6075 4450) BN 13
J 0
(-6087 4458);
DISPLAY 0.489362 (-6087 4458);
PAINT GREEN (-6087 4458);
FORCEPROP 2 LAST CDS_LIB mstr_standard
J 0
(-6025 4450);
DISPLAY 0.723404 (-6025 4450);
PAINT MONO (-6025 4450);
DISPLAY INVISIBLE (-6025 4450);
FORCEPROP 1 LAST BODY_TYPE PLUMBING
J 0
(-6025 4500);
DISPLAY 0.872340 (-6025 4500);
PAINT GREEN (-6025 4500);
DISPLAY INVISIBLE (-6025 4500);
FORCEPROP 1 LAST HDL_TAP TRUE
J 0
(-5700 4325);
DISPLAY 0.872340 (-5700 4325);
DISPLAY INVISIBLE (-5700 4325);
FORCEPROP 1 LAST PATH I106
J 0
(-6027 4450);
DISPLAY 0.872340 (-6027 4450);
PAINT GREEN (-6027 4450);
DISPLAY INVISIBLE (-6027 4450);
FORCEADD TAP..1
(-6025 4500);
FORCEPROP 3 LASTPIN (-6075 4500) SIG_NAME M_H_CPU0_SA_DQ<14>
J 0
(-6065 4510);
DISPLAY 0.659574 (-6065 4510);
PAINT MONO (-6065 4510);
DISPLAY INVISIBLE (-6065 4510);
FORCEPROP 1 LASTPIN (-6075 4500) BN 14
J 0
(-6087 4508);
DISPLAY 0.489362 (-6087 4508);
PAINT GREEN (-6087 4508);
FORCEPROP 2 LAST CDS_LIB mstr_standard
J 0
(-6025 4500);
DISPLAY 0.723404 (-6025 4500);
PAINT MONO (-6025 4500);
DISPLAY INVISIBLE (-6025 4500);
FORCEPROP 1 LAST BODY_TYPE PLUMBING
J 0
(-6025 4550);
DISPLAY 0.872340 (-6025 4550);
PAINT GREEN (-6025 4550);
DISPLAY INVISIBLE (-6025 4550);
FORCEPROP 1 LAST HDL_TAP TRUE
J 0
(-5700 4375);
DISPLAY 0.872340 (-5700 4375);
DISPLAY INVISIBLE (-5700 4375);
FORCEPROP 1 LAST PATH I107
J 0
(-6027 4500);
DISPLAY 0.872340 (-6027 4500);
PAINT GREEN (-6027 4500);
DISPLAY INVISIBLE (-6027 4500);
FORCEADD TAP..1
(-6025 4300);
FORCEPROP 3 LASTPIN (-6075 4300) SIG_NAME M_H_CPU0_SA_DQ<10>
J 0
(-6065 4310);
DISPLAY 0.659574 (-6065 4310);
PAINT MONO (-6065 4310);
DISPLAY INVISIBLE (-6065 4310);
FORCEPROP 1 LASTPIN (-6075 4300) BN 10
J 0
(-6087 4308);
DISPLAY 0.489362 (-6087 4308);
PAINT GREEN (-6087 4308);
FORCEPROP 2 LAST CDS_LIB mstr_standard
J 0
(-6025 4300);
DISPLAY 0.723404 (-6025 4300);
PAINT MONO (-6025 4300);
DISPLAY INVISIBLE (-6025 4300);
FORCEPROP 1 LAST BODY_TYPE PLUMBING
J 0
(-6025 4350);
DISPLAY 0.872340 (-6025 4350);
PAINT GREEN (-6025 4350);
DISPLAY INVISIBLE (-6025 4350);
FORCEPROP 1 LAST HDL_TAP TRUE
J 0
(-5700 4175);
DISPLAY 0.872340 (-5700 4175);
DISPLAY INVISIBLE (-5700 4175);
FORCEPROP 1 LAST PATH I108
J 0
(-6027 4300);
DISPLAY 0.872340 (-6027 4300);
PAINT GREEN (-6027 4300);
DISPLAY INVISIBLE (-6027 4300);
FORCEADD TAP..1
(-6025 4750);
FORCEPROP 3 LASTPIN (-6075 4750) SIG_NAME M_H_CPU0_SA_DQ<19>
J 0
(-6065 4760);
DISPLAY 0.659574 (-6065 4760);
PAINT MONO (-6065 4760);
DISPLAY INVISIBLE (-6065 4760);
FORCEPROP 1 LASTPIN (-6075 4750) BN 19
J 0
(-6087 4758);
DISPLAY 0.489362 (-6087 4758);
PAINT GREEN (-6087 4758);
FORCEPROP 2 LAST CDS_LIB mstr_standard
J 0
(-6025 4750);
DISPLAY 0.723404 (-6025 4750);
PAINT MONO (-6025 4750);
DISPLAY INVISIBLE (-6025 4750);
FORCEPROP 1 LAST BODY_TYPE PLUMBING
J 0
(-6025 4800);
DISPLAY 0.872340 (-6025 4800);
PAINT GREEN (-6025 4800);
DISPLAY INVISIBLE (-6025 4800);
FORCEPROP 1 LAST HDL_TAP TRUE
J 0
(-5700 4625);
DISPLAY 0.872340 (-5700 4625);
DISPLAY INVISIBLE (-5700 4625);
FORCEPROP 1 LAST PATH I109
J 0
(-6027 4750);
DISPLAY 0.872340 (-6027 4750);
PAINT GREEN (-6027 4750);
DISPLAY INVISIBLE (-6027 4750);
FORCEADD OFFPAGE..6
(-8325 4000);
FORCEPROP 2 LAST $XR0 17 
J 0
(-8574 4000);
DISPLAY 0.638298 (-8574 4000);
PAINT MONO (-8574 4000);
FORCEPROP 2 LAST CDS_LIB mstr_standard
J 0
(-8325 4000);
DISPLAY 0.723404 (-8325 4000);
PAINT MONO (-8325 4000);
DISPLAY INVISIBLE (-8325 4000);
FORCEPROP 1 LAST OFFPAGE TRUE
J 0
(-8000 3875);
DISPLAY 0.872340 (-8000 3875);
PAINT GREEN (-8000 3875);
DISPLAY INVISIBLE (-8000 3875);
FORCEPROP 1 LAST COMMENT_BODY TRUE
J 0
(-8225 3925);
DISPLAY 0.872340 (-8225 3925);
PAINT GREEN (-8225 3925);
DISPLAY INVISIBLE (-8225 3925);
FORCEPROP 2 LAST PATH I11
J 0
(-8275 4075);
DISPLAY 1.021277 (-8275 4075);
DISPLAY INVISIBLE (-8275 4075);
FORCEADD TAP..1
(-6025 4600);
FORCEPROP 3 LASTPIN (-6075 4600) SIG_NAME M_H_CPU0_SA_DQ<16>
J 0
(-6065 4610);
DISPLAY 0.659574 (-6065 4610);
PAINT MONO (-6065 4610);
DISPLAY INVISIBLE (-6065 4610);
FORCEPROP 1 LASTPIN (-6075 4600) BN 16
J 0
(-6087 4608);
DISPLAY 0.489362 (-6087 4608);
PAINT GREEN (-6087 4608);
FORCEPROP 2 LAST CDS_LIB mstr_standard
J 0
(-6025 4600);
DISPLAY 0.723404 (-6025 4600);
PAINT MONO (-6025 4600);
DISPLAY INVISIBLE (-6025 4600);
FORCEPROP 1 LAST BODY_TYPE PLUMBING
J 0
(-6025 4650);
DISPLAY 0.872340 (-6025 4650);
PAINT GREEN (-6025 4650);
DISPLAY INVISIBLE (-6025 4650);
FORCEPROP 1 LAST HDL_TAP TRUE
J 0
(-5700 4475);
DISPLAY 0.872340 (-5700 4475);
DISPLAY INVISIBLE (-5700 4475);
FORCEPROP 1 LAST PATH I110
J 0
(-6027 4600);
DISPLAY 0.872340 (-6027 4600);
PAINT GREEN (-6027 4600);
DISPLAY INVISIBLE (-6027 4600);
FORCEADD TAP..1
(-6025 4700);
FORCEPROP 3 LASTPIN (-6075 4700) SIG_NAME M_H_CPU0_SA_DQ<18>
J 0
(-6065 4710);
DISPLAY 0.659574 (-6065 4710);
PAINT MONO (-6065 4710);
DISPLAY INVISIBLE (-6065 4710);
FORCEPROP 1 LASTPIN (-6075 4700) BN 18
J 0
(-6087 4708);
DISPLAY 0.489362 (-6087 4708);
PAINT GREEN (-6087 4708);
FORCEPROP 2 LAST CDS_LIB mstr_standard
J 0
(-6025 4700);
DISPLAY 0.723404 (-6025 4700);
PAINT MONO (-6025 4700);
DISPLAY INVISIBLE (-6025 4700);
FORCEPROP 1 LAST BODY_TYPE PLUMBING
J 0
(-6025 4750);
DISPLAY 0.872340 (-6025 4750);
PAINT GREEN (-6025 4750);
DISPLAY INVISIBLE (-6025 4750);
FORCEPROP 1 LAST HDL_TAP TRUE
J 0
(-5700 4575);
DISPLAY 0.872340 (-5700 4575);
DISPLAY INVISIBLE (-5700 4575);
FORCEPROP 1 LAST PATH I111
J 0
(-6027 4700);
DISPLAY 0.872340 (-6027 4700);
PAINT GREEN (-6027 4700);
DISPLAY INVISIBLE (-6027 4700);
FORCEADD TAP..1
(-6025 4650);
FORCEPROP 3 LASTPIN (-6075 4650) SIG_NAME M_H_CPU0_SA_DQ<17>
J 0
(-6065 4660);
DISPLAY 0.659574 (-6065 4660);
PAINT MONO (-6065 4660);
DISPLAY INVISIBLE (-6065 4660);
FORCEPROP 1 LASTPIN (-6075 4650) BN 17
J 0
(-6087 4658);
DISPLAY 0.489362 (-6087 4658);
PAINT GREEN (-6087 4658);
FORCEPROP 2 LAST CDS_LIB mstr_standard
J 0
(-6025 4650);
DISPLAY 0.723404 (-6025 4650);
PAINT MONO (-6025 4650);
DISPLAY INVISIBLE (-6025 4650);
FORCEPROP 1 LAST BODY_TYPE PLUMBING
J 0
(-6025 4700);
DISPLAY 0.872340 (-6025 4700);
PAINT GREEN (-6025 4700);
DISPLAY INVISIBLE (-6025 4700);
FORCEPROP 1 LAST HDL_TAP TRUE
J 0
(-5700 4525);
DISPLAY 0.872340 (-5700 4525);
DISPLAY INVISIBLE (-5700 4525);
FORCEPROP 1 LAST PATH I112
J 0
(-6027 4650);
DISPLAY 0.872340 (-6027 4650);
PAINT GREEN (-6027 4650);
DISPLAY INVISIBLE (-6027 4650);
FORCEADD TAP..1
(-6025 4550);
FORCEPROP 3 LASTPIN (-6075 4550) SIG_NAME M_H_CPU0_SA_DQ<15>
J 0
(-6065 4560);
DISPLAY 0.659574 (-6065 4560);
PAINT MONO (-6065 4560);
DISPLAY INVISIBLE (-6065 4560);
FORCEPROP 1 LASTPIN (-6075 4550) BN 15
J 0
(-6087 4558);
DISPLAY 0.489362 (-6087 4558);
PAINT GREEN (-6087 4558);
FORCEPROP 2 LAST CDS_LIB mstr_standard
J 0
(-6025 4550);
DISPLAY 0.723404 (-6025 4550);
PAINT MONO (-6025 4550);
DISPLAY INVISIBLE (-6025 4550);
FORCEPROP 1 LAST BODY_TYPE PLUMBING
J 0
(-6025 4600);
DISPLAY 0.872340 (-6025 4600);
PAINT GREEN (-6025 4600);
DISPLAY INVISIBLE (-6025 4600);
FORCEPROP 1 LAST HDL_TAP TRUE
J 0
(-5700 4425);
DISPLAY 0.872340 (-5700 4425);
DISPLAY INVISIBLE (-5700 4425);
FORCEPROP 1 LAST PATH I113
J 0
(-6027 4550);
DISPLAY 0.872340 (-6027 4550);
PAINT GREEN (-6027 4550);
DISPLAY INVISIBLE (-6027 4550);
FORCEADD TAP..1
(-6025 4800);
FORCEPROP 3 LASTPIN (-6075 4800) SIG_NAME M_H_CPU0_SA_DQ<20>
J 0
(-6065 4810);
DISPLAY 0.659574 (-6065 4810);
PAINT MONO (-6065 4810);
DISPLAY INVISIBLE (-6065 4810);
FORCEPROP 1 LASTPIN (-6075 4800) BN 20
J 0
(-6087 4808);
DISPLAY 0.489362 (-6087 4808);
PAINT GREEN (-6087 4808);
FORCEPROP 2 LAST CDS_LIB mstr_standard
J 0
(-6025 4800);
DISPLAY 0.723404 (-6025 4800);
PAINT MONO (-6025 4800);
DISPLAY INVISIBLE (-6025 4800);
FORCEPROP 1 LAST BODY_TYPE PLUMBING
J 0
(-6025 4850);
DISPLAY 0.872340 (-6025 4850);
PAINT GREEN (-6025 4850);
DISPLAY INVISIBLE (-6025 4850);
FORCEPROP 1 LAST HDL_TAP TRUE
J 0
(-5700 4675);
DISPLAY 0.872340 (-5700 4675);
DISPLAY INVISIBLE (-5700 4675);
FORCEPROP 1 LAST PATH I114
J 0
(-6027 4800);
DISPLAY 0.872340 (-6027 4800);
PAINT GREEN (-6027 4800);
DISPLAY INVISIBLE (-6027 4800);
FORCEADD TAP..1
(-6025 4850);
FORCEPROP 3 LASTPIN (-6075 4850) SIG_NAME M_H_CPU0_SA_DQ<21>
J 0
(-6065 4860);
DISPLAY 0.659574 (-6065 4860);
PAINT MONO (-6065 4860);
DISPLAY INVISIBLE (-6065 4860);
FORCEPROP 1 LASTPIN (-6075 4850) BN 21
J 0
(-6087 4858);
DISPLAY 0.489362 (-6087 4858);
PAINT GREEN (-6087 4858);
FORCEPROP 2 LAST CDS_LIB mstr_standard
J 0
(-6025 4850);
DISPLAY 0.723404 (-6025 4850);
PAINT MONO (-6025 4850);
DISPLAY INVISIBLE (-6025 4850);
FORCEPROP 1 LAST BODY_TYPE PLUMBING
J 0
(-6025 4900);
DISPLAY 0.872340 (-6025 4900);
PAINT GREEN (-6025 4900);
DISPLAY INVISIBLE (-6025 4900);
FORCEPROP 1 LAST HDL_TAP TRUE
J 0
(-5700 4725);
DISPLAY 0.872340 (-5700 4725);
DISPLAY INVISIBLE (-5700 4725);
FORCEPROP 1 LAST PATH I115
J 0
(-6027 4850);
DISPLAY 0.872340 (-6027 4850);
PAINT GREEN (-6027 4850);
DISPLAY INVISIBLE (-6027 4850);
FORCEADD TAP..1
(-6025 4900);
FORCEPROP 3 LASTPIN (-6075 4900) SIG_NAME M_H_CPU0_SA_DQ<22>
J 0
(-6065 4910);
DISPLAY 0.659574 (-6065 4910);
PAINT MONO (-6065 4910);
DISPLAY INVISIBLE (-6065 4910);
FORCEPROP 1 LASTPIN (-6075 4900) BN 22
J 0
(-6087 4908);
DISPLAY 0.489362 (-6087 4908);
PAINT GREEN (-6087 4908);
FORCEPROP 2 LAST CDS_LIB mstr_standard
J 0
(-6025 4900);
DISPLAY 0.723404 (-6025 4900);
PAINT MONO (-6025 4900);
DISPLAY INVISIBLE (-6025 4900);
FORCEPROP 1 LAST BODY_TYPE PLUMBING
J 0
(-6025 4950);
DISPLAY 0.872340 (-6025 4950);
PAINT GREEN (-6025 4950);
DISPLAY INVISIBLE (-6025 4950);
FORCEPROP 1 LAST HDL_TAP TRUE
J 0
(-5700 4775);
DISPLAY 0.872340 (-5700 4775);
DISPLAY INVISIBLE (-5700 4775);
FORCEPROP 1 LAST PATH I116
J 0
(-6027 4900);
DISPLAY 0.872340 (-6027 4900);
PAINT GREEN (-6027 4900);
DISPLAY INVISIBLE (-6027 4900);
FORCEADD TAP..1
(-6025 5050);
FORCEPROP 3 LASTPIN (-6075 5050) SIG_NAME M_H_CPU0_SA_DQ<25>
J 0
(-6065 5060);
DISPLAY 0.659574 (-6065 5060);
PAINT MONO (-6065 5060);
DISPLAY INVISIBLE (-6065 5060);
FORCEPROP 1 LASTPIN (-6075 5050) BN 25
J 0
(-6087 5058);
DISPLAY 0.489362 (-6087 5058);
PAINT GREEN (-6087 5058);
FORCEPROP 2 LAST CDS_LIB mstr_standard
J 0
(-6025 5050);
DISPLAY 0.723404 (-6025 5050);
PAINT MONO (-6025 5050);
DISPLAY INVISIBLE (-6025 5050);
FORCEPROP 1 LAST BODY_TYPE PLUMBING
J 0
(-6025 5100);
DISPLAY 0.872340 (-6025 5100);
PAINT GREEN (-6025 5100);
DISPLAY INVISIBLE (-6025 5100);
FORCEPROP 1 LAST HDL_TAP TRUE
J 0
(-5700 4925);
DISPLAY 0.872340 (-5700 4925);
DISPLAY INVISIBLE (-5700 4925);
FORCEPROP 1 LAST PATH I117
J 0
(-6027 5050);
DISPLAY 0.872340 (-6027 5050);
PAINT GREEN (-6027 5050);
DISPLAY INVISIBLE (-6027 5050);
FORCEADD TAP..1
(-6025 4950);
FORCEPROP 3 LASTPIN (-6075 4950) SIG_NAME M_H_CPU0_SA_DQ<23>
J 0
(-6065 4960);
DISPLAY 0.659574 (-6065 4960);
PAINT MONO (-6065 4960);
DISPLAY INVISIBLE (-6065 4960);
FORCEPROP 1 LASTPIN (-6075 4950) BN 23
J 0
(-6087 4958);
DISPLAY 0.489362 (-6087 4958);
PAINT GREEN (-6087 4958);
FORCEPROP 2 LAST CDS_LIB mstr_standard
J 0
(-6025 4950);
DISPLAY 0.723404 (-6025 4950);
PAINT MONO (-6025 4950);
DISPLAY INVISIBLE (-6025 4950);
FORCEPROP 1 LAST BODY_TYPE PLUMBING
J 0
(-6025 5000);
DISPLAY 0.872340 (-6025 5000);
PAINT GREEN (-6025 5000);
DISPLAY INVISIBLE (-6025 5000);
FORCEPROP 1 LAST HDL_TAP TRUE
J 0
(-5700 4825);
DISPLAY 0.872340 (-5700 4825);
DISPLAY INVISIBLE (-5700 4825);
FORCEPROP 1 LAST PATH I118
J 0
(-6027 4950);
DISPLAY 0.872340 (-6027 4950);
PAINT GREEN (-6027 4950);
DISPLAY INVISIBLE (-6027 4950);
FORCEADD TAP..1
(-6025 5000);
FORCEPROP 3 LASTPIN (-6075 5000) SIG_NAME M_H_CPU0_SA_DQ<24>
J 0
(-6065 5010);
DISPLAY 0.659574 (-6065 5010);
PAINT MONO (-6065 5010);
DISPLAY INVISIBLE (-6065 5010);
FORCEPROP 1 LASTPIN (-6075 5000) BN 24
J 0
(-6087 5008);
DISPLAY 0.489362 (-6087 5008);
PAINT GREEN (-6087 5008);
FORCEPROP 2 LAST CDS_LIB mstr_standard
J 0
(-6025 5000);
DISPLAY 0.723404 (-6025 5000);
PAINT MONO (-6025 5000);
DISPLAY INVISIBLE (-6025 5000);
FORCEPROP 1 LAST BODY_TYPE PLUMBING
J 0
(-6025 5050);
DISPLAY 0.872340 (-6025 5050);
PAINT GREEN (-6025 5050);
DISPLAY INVISIBLE (-6025 5050);
FORCEPROP 1 LAST HDL_TAP TRUE
J 0
(-5700 4875);
DISPLAY 0.872340 (-5700 4875);
DISPLAY INVISIBLE (-5700 4875);
FORCEPROP 1 LAST PATH I119
J 0
(-6027 5000);
DISPLAY 0.872340 (-6027 5000);
PAINT GREEN (-6027 5000);
DISPLAY INVISIBLE (-6027 5000);
FORCEADD OFFPAGE..1
(-8325 4050);
FORCEPROP 2 LAST $XR0 17 
J 0
(-8546 4050);
DISPLAY 0.638298 (-8546 4050);
PAINT MONO (-8546 4050);
FORCEPROP 2 LAST CDS_LIB mstr_standard
J 0
(-8325 4050);
DISPLAY 0.808511 (-8325 4050);
DISPLAY INVISIBLE (-8325 4050);
FORCEPROP 1 LAST OFFPAGE TRUE
J 0
(-8000 3925);
DISPLAY 0.872340 (-8000 3925);
PAINT GREEN (-8000 3925);
DISPLAY INVISIBLE (-8000 3925);
FORCEPROP 1 LAST COMMENT_BODY TRUE
J 0
(-8200 3950);
DISPLAY 0.872340 (-8200 3950);
PAINT GREEN (-8200 3950);
DISPLAY INVISIBLE (-8200 3950);
FORCEPROP 2 LAST PATH I12
J 0
(-8275 4125);
DISPLAY 1.021277 (-8275 4125);
DISPLAY INVISIBLE (-8275 4125);
FORCEADD TAP..1
(-6025 5250);
FORCEPROP 3 LASTPIN (-6075 5250) SIG_NAME M_H_CPU0_SA_DQ<29>
J 0
(-6065 5260);
DISPLAY 0.659574 (-6065 5260);
PAINT MONO (-6065 5260);
DISPLAY INVISIBLE (-6065 5260);
FORCEPROP 1 LASTPIN (-6075 5250) BN 29
J 0
(-6087 5258);
DISPLAY 0.489362 (-6087 5258);
PAINT GREEN (-6087 5258);
FORCEPROP 2 LAST CDS_LIB mstr_standard
J 0
(-6025 5250);
DISPLAY 0.723404 (-6025 5250);
PAINT MONO (-6025 5250);
DISPLAY INVISIBLE (-6025 5250);
FORCEPROP 1 LAST BODY_TYPE PLUMBING
J 0
(-6025 5300);
DISPLAY 0.872340 (-6025 5300);
PAINT GREEN (-6025 5300);
DISPLAY INVISIBLE (-6025 5300);
FORCEPROP 1 LAST HDL_TAP TRUE
J 0
(-5700 5125);
DISPLAY 0.872340 (-5700 5125);
DISPLAY INVISIBLE (-5700 5125);
FORCEPROP 1 LAST PATH I120
J 0
(-6027 5250);
DISPLAY 0.872340 (-6027 5250);
PAINT GREEN (-6027 5250);
DISPLAY INVISIBLE (-6027 5250);
FORCEADD TAP..1
(-6025 5300);
FORCEPROP 3 LASTPIN (-6075 5300) SIG_NAME M_H_CPU0_SA_DQ<30>
J 0
(-6065 5310);
DISPLAY 0.659574 (-6065 5310);
PAINT MONO (-6065 5310);
DISPLAY INVISIBLE (-6065 5310);
FORCEPROP 1 LASTPIN (-6075 5300) BN 30
J 0
(-6087 5308);
DISPLAY 0.489362 (-6087 5308);
PAINT GREEN (-6087 5308);
FORCEPROP 2 LAST CDS_LIB mstr_standard
J 0
(-6025 5300);
DISPLAY 0.723404 (-6025 5300);
PAINT MONO (-6025 5300);
DISPLAY INVISIBLE (-6025 5300);
FORCEPROP 1 LAST BODY_TYPE PLUMBING
J 0
(-6025 5350);
DISPLAY 0.872340 (-6025 5350);
PAINT GREEN (-6025 5350);
DISPLAY INVISIBLE (-6025 5350);
FORCEPROP 1 LAST HDL_TAP TRUE
J 0
(-5700 5175);
DISPLAY 0.872340 (-5700 5175);
DISPLAY INVISIBLE (-5700 5175);
FORCEPROP 1 LAST PATH I121
J 0
(-6027 5300);
DISPLAY 0.872340 (-6027 5300);
PAINT GREEN (-6027 5300);
DISPLAY INVISIBLE (-6027 5300);
FORCEADD TAP..1
(-6025 5200);
FORCEPROP 3 LASTPIN (-6075 5200) SIG_NAME M_H_CPU0_SA_DQ<28>
J 0
(-6065 5210);
DISPLAY 0.659574 (-6065 5210);
PAINT MONO (-6065 5210);
DISPLAY INVISIBLE (-6065 5210);
FORCEPROP 1 LASTPIN (-6075 5200) BN 28
J 0
(-6087 5208);
DISPLAY 0.489362 (-6087 5208);
PAINT GREEN (-6087 5208);
FORCEPROP 2 LAST CDS_LIB mstr_standard
J 0
(-6025 5200);
DISPLAY 0.723404 (-6025 5200);
PAINT MONO (-6025 5200);
DISPLAY INVISIBLE (-6025 5200);
FORCEPROP 1 LAST BODY_TYPE PLUMBING
J 0
(-6025 5250);
DISPLAY 0.872340 (-6025 5250);
PAINT GREEN (-6025 5250);
DISPLAY INVISIBLE (-6025 5250);
FORCEPROP 1 LAST HDL_TAP TRUE
J 0
(-5700 5075);
DISPLAY 0.872340 (-5700 5075);
DISPLAY INVISIBLE (-5700 5075);
FORCEPROP 1 LAST PATH I122
J 0
(-6027 5200);
DISPLAY 0.872340 (-6027 5200);
PAINT GREEN (-6027 5200);
DISPLAY INVISIBLE (-6027 5200);
FORCEADD TAP..1
(-6025 5150);
FORCEPROP 3 LASTPIN (-6075 5150) SIG_NAME M_H_CPU0_SA_DQ<27>
J 0
(-6065 5160);
DISPLAY 0.659574 (-6065 5160);
PAINT MONO (-6065 5160);
DISPLAY INVISIBLE (-6065 5160);
FORCEPROP 1 LASTPIN (-6075 5150) BN 27
J 0
(-6087 5158);
DISPLAY 0.489362 (-6087 5158);
PAINT GREEN (-6087 5158);
FORCEPROP 2 LAST CDS_LIB mstr_standard
J 0
(-6025 5150);
DISPLAY 0.723404 (-6025 5150);
PAINT MONO (-6025 5150);
DISPLAY INVISIBLE (-6025 5150);
FORCEPROP 1 LAST BODY_TYPE PLUMBING
J 0
(-6025 5200);
DISPLAY 0.872340 (-6025 5200);
PAINT GREEN (-6025 5200);
DISPLAY INVISIBLE (-6025 5200);
FORCEPROP 1 LAST HDL_TAP TRUE
J 0
(-5700 5025);
DISPLAY 0.872340 (-5700 5025);
DISPLAY INVISIBLE (-5700 5025);
FORCEPROP 1 LAST PATH I123
J 0
(-6027 5150);
DISPLAY 0.872340 (-6027 5150);
PAINT GREEN (-6027 5150);
DISPLAY INVISIBLE (-6027 5150);
FORCEADD TAP..1
(-6025 5100);
FORCEPROP 3 LASTPIN (-6075 5100) SIG_NAME M_H_CPU0_SA_DQ<26>
J 0
(-6065 5110);
DISPLAY 0.659574 (-6065 5110);
PAINT MONO (-6065 5110);
DISPLAY INVISIBLE (-6065 5110);
FORCEPROP 1 LASTPIN (-6075 5100) BN 26
J 0
(-6087 5108);
DISPLAY 0.489362 (-6087 5108);
PAINT GREEN (-6087 5108);
FORCEPROP 2 LAST CDS_LIB mstr_standard
J 0
(-6025 5100);
DISPLAY 0.723404 (-6025 5100);
PAINT MONO (-6025 5100);
DISPLAY INVISIBLE (-6025 5100);
FORCEPROP 1 LAST BODY_TYPE PLUMBING
J 0
(-6025 5150);
DISPLAY 0.872340 (-6025 5150);
PAINT GREEN (-6025 5150);
DISPLAY INVISIBLE (-6025 5150);
FORCEPROP 1 LAST HDL_TAP TRUE
J 0
(-5700 4975);
DISPLAY 0.872340 (-5700 4975);
DISPLAY INVISIBLE (-5700 4975);
FORCEPROP 1 LAST PATH I124
J 0
(-6027 5100);
DISPLAY 0.872340 (-6027 5100);
PAINT GREEN (-6027 5100);
DISPLAY INVISIBLE (-6027 5100);
FORCEADD TAP..1
(-6025 5350);
FORCEPROP 3 LASTPIN (-6075 5350) SIG_NAME M_H_CPU0_SA_DQ<31>
J 0
(-6065 5360);
DISPLAY 0.659574 (-6065 5360);
PAINT MONO (-6065 5360);
DISPLAY INVISIBLE (-6065 5360);
FORCEPROP 1 LASTPIN (-6075 5350) BN 31
J 0
(-6087 5358);
DISPLAY 0.489362 (-6087 5358);
PAINT GREEN (-6087 5358);
FORCEPROP 2 LAST CDS_LIB mstr_standard
J 0
(-6025 5350);
DISPLAY 0.723404 (-6025 5350);
PAINT MONO (-6025 5350);
DISPLAY INVISIBLE (-6025 5350);
FORCEPROP 1 LAST BODY_TYPE PLUMBING
J 0
(-6025 5400);
DISPLAY 0.872340 (-6025 5400);
PAINT GREEN (-6025 5400);
DISPLAY INVISIBLE (-6025 5400);
FORCEPROP 1 LAST HDL_TAP TRUE
J 0
(-5700 5225);
DISPLAY 0.872340 (-5700 5225);
DISPLAY INVISIBLE (-5700 5225);
FORCEPROP 1 LAST PATH I125
J 0
(-6027 5350);
DISPLAY 0.872340 (-6027 5350);
PAINT GREEN (-6027 5350);
DISPLAY INVISIBLE (-6027 5350);
FORCEADD OFFPAGE..3
(-5350 5400);
FORCEPROP 2 LAST $XR0 17 
J 0
(-5136 5400);
DISPLAY 0.638298 (-5136 5400);
PAINT MONO (-5136 5400);
FORCEPROP 2 LAST CDS_LIB mstr_standard
J 0
(-5350 5400);
DISPLAY 0.723404 (-5350 5400);
PAINT MONO (-5350 5400);
DISPLAY INVISIBLE (-5350 5400);
FORCEPROP 1 LAST OFFPAGE TRUE
J 0
(-5025 5275);
DISPLAY 0.872340 (-5025 5275);
PAINT GREEN (-5025 5275);
DISPLAY INVISIBLE (-5025 5275);
FORCEPROP 1 LAST COMMENT_BODY TRUE
J 0
(-5400 5300);
DISPLAY 0.872340 (-5400 5300);
PAINT GREEN (-5400 5300);
DISPLAY INVISIBLE (-5400 5300);
FORCEPROP 2 LAST PATH I126
J 0
(-5150 5475);
DISPLAY 1.021277 (-5150 5475);
DISPLAY INVISIBLE (-5150 5475);
FORCEADD OFFPAGE..5
(-7200 1350);
FORCEPROP 2 LAST $XR0 93 
J 0
(-7424 1350);
DISPLAY 0.638298 (-7424 1350);
PAINT MONO (-7424 1350);
FORCEPROP 2 LAST BOM_COST MEM
J 0
(-7275 1425);
DISPLAY 0.808511 (-7275 1425);
DISPLAY INVISIBLE (-7275 1425);
FORCEPROP 2 LAST CDS_LIB mstr_standard
J 0
(-7200 1350);
DISPLAY 0.808511 (-7200 1350);
DISPLAY INVISIBLE (-7200 1350);
FORCEPROP 1 LAST OFFPAGE TRUE
J 0
(-6875 1225);
DISPLAY 0.872340 (-6875 1225);
PAINT GREEN (-6875 1225);
DISPLAY INVISIBLE (-6875 1225);
FORCEPROP 1 LAST COMMENT_BODY TRUE
J 0
(-7100 1275);
DISPLAY 0.872340 (-7100 1275);
PAINT GREEN (-7100 1275);
DISPLAY INVISIBLE (-7100 1275);
FORCEPROP 2 LAST PATH I127
J 0
(-7450 1400);
DISPLAY 1.021277 (-7450 1400);
DISPLAY INVISIBLE (-7450 1400);
FORCEADD GND..1
(-6425 875);
FORCEPROP 3 LASTPIN (-6425 925) SIG_NAME GND\g
J 0
(-6415 935);
DISPLAY 0.659574 (-6415 935);
PAINT MONO (-6415 935);
DISPLAY INVISIBLE (-6415 935);
FORCEPROP 1 LAST VOLTAGE 0.0
J 0
(-6470 832);
DISPLAY 0.723404 (-6470 832);
PAINT SKYBLUE (-6470 832);
DISPLAY INVISIBLE (-6470 832);
FORCEPROP 2 LAST BOM_COST MEM
J 0
(-6525 950);
DISPLAY 0.808511 (-6525 950);
DISPLAY INVISIBLE (-6525 950);
FORCEPROP 2 LAST CDS_LIB mstr_symbols
J 0
(-6425 875);
DISPLAY 0.808511 (-6425 875);
DISPLAY INVISIBLE (-6425 875);
FORCEPROP 1 LAST SIZE 1B
J 0
(-6350 825);
DISPLAY 0.851064 (-6350 825);
PAINT GREEN (-6350 825);
DISPLAY INVISIBLE (-6350 825);
FORCEPROP 1 LAST BODY_TYPE PLUMBING
J 0
(-6470 832);
DISPLAY 0.340426 (-6470 832);
PAINT GREEN (-6470 832);
DISPLAY INVISIBLE (-6470 832);
FORCEPROP 1 LAST HDL_POWER GND
J 0
(-6425 1025);
DISPLAY 0.851064 (-6425 1025);
PAINT GREEN (-6425 1025);
DISPLAY INVISIBLE (-6425 1025);
FORCEPROP 1 LAST PATH I128
J 0
(-6350 875);
DISPLAY 0.872340 (-6350 875);
PAINT AQUA (-6350 875);
DISPLAY INVISIBLE (-6350 875);
FORCEADD Q_RES..2
(-6425 1175);
FORCEPROP 1 LAST LOCATION R765
J 0
(-6380 1300);
DISPLAY 0.489362 (-6380 1300);
PAINT SKYBLUE (-6380 1300);
FORCEPROP 0 LAST $SEC 1
J 0
(-6375 1350);
DISPLAY 0.680851 (-6375 1350);
PAINT MONO (-6375 1350);
DISPLAY INVISIBLE (-6375 1350);
FORCEPROP 0 LAST CDS_SEC 1
J 0
(-6375 1350);
DISPLAY 1.021277 (-6375 1350);
DISPLAY INVISIBLE (-6375 1350);
FORCEPROP 1 LASTPIN (-6425 1275) $PN 1
J 0
(-6420 1237);
DISPLAY 0.489362 (-6420 1237);
PAINT MONO (-6420 1237);
FORCEPROP 1 LASTPIN (-6425 1075) $PN 2
J 0
(-6420 1085);
DISPLAY 0.489362 (-6420 1085);
PAINT MONO (-6420 1085);
FORCEPROP 1 LAST PACK_TYPE 0402LF
J 0
(-6385 1000);
DISPLAY 0.489362 (-6385 1000);
PAINT SKYBLUE (-6385 1000);
FORCEPROP 1 LAST VALUE 15.4K
J 0
(-6380 1250);
DISPLAY 0.489362 (-6380 1250);
PAINT SKYBLUE (-6380 1250);
FORCEPROP 1 LAST TOLERANCE 1%
J 0
(-6380 1200);
DISPLAY 0.489362 (-6380 1200);
PAINT SKYBLUE (-6380 1200);
FORCEPROP 1 LAST MATERIAL CHIP
J 0
(-6385 1100);
DISPLAY 0.489362 (-6385 1100);
PAINT SKYBLUE (-6385 1100);
FORCEPROP 1 LAST WATTAGE 1/16W
J 0
(-6385 1150);
DISPLAY 0.489362 (-6385 1150);
PAINT SKYBLUE (-6385 1150);
FORCEPROP 2 LAST CDS_LIB pure_quanta
J 0
(-6425 1175);
DISPLAY INVISIBLE (-6425 1175);
FORCEPROP 1 LAST PATH I129
J 0
(-6375 1350);
DISPLAY 0.978723 (-6375 1350);
PAINT WHITE (-6375 1350);
DISPLAY INVISIBLE (-6375 1350);
FORCEPROP 1 LAST PART_NUMBER CS31542FB02
J 0
(-6385 1050);
DISPLAY 0.489362 (-6385 1050);
PAINT SKYBLUE (-6385 1050);
DISPLAY INVISIBLE (-6385 1050);
FORCEADD OFFPAGE..1
(-8325 4250);
FORCEPROP 2 LAST $XR0 17 
J 0
(-8546 4250);
DISPLAY 0.638298 (-8546 4250);
PAINT MONO (-8546 4250);
FORCEPROP 2 LAST CDS_LIB mstr_standard
J 0
(-8325 4250);
DISPLAY 0.723404 (-8325 4250);
PAINT MONO (-8325 4250);
DISPLAY INVISIBLE (-8325 4250);
FORCEPROP 1 LAST OFFPAGE TRUE
J 0
(-8000 4125);
DISPLAY 0.872340 (-8000 4125);
PAINT GREEN (-8000 4125);
DISPLAY INVISIBLE (-8000 4125);
FORCEPROP 1 LAST COMMENT_BODY TRUE
J 0
(-8200 4150);
DISPLAY 0.872340 (-8200 4150);
PAINT GREEN (-8200 4150);
DISPLAY INVISIBLE (-8200 4150);
FORCEPROP 2 LAST PATH I13
J 0
(-8275 4325);
DISPLAY 1.021277 (-8275 4325);
DISPLAY INVISIBLE (-8275 4325);
FORCEADD OFFPAGE..1
(-8325 4100);
FORCEPROP 2 LAST $XR0 17 
J 0
(-8546 4100);
DISPLAY 0.638298 (-8546 4100);
PAINT MONO (-8546 4100);
FORCEPROP 2 LAST CDS_LIB mstr_standard
J 0
(-8325 4100);
DISPLAY 0.723404 (-8325 4100);
PAINT MONO (-8325 4100);
DISPLAY INVISIBLE (-8325 4100);
FORCEPROP 1 LAST OFFPAGE TRUE
J 0
(-8000 3975);
DISPLAY 0.872340 (-8000 3975);
PAINT GREEN (-8000 3975);
DISPLAY INVISIBLE (-8000 3975);
FORCEPROP 1 LAST COMMENT_BODY TRUE
J 0
(-8200 4000);
DISPLAY 0.872340 (-8200 4000);
PAINT GREEN (-8200 4000);
DISPLAY INVISIBLE (-8200 4000);
FORCEPROP 2 LAST PATH I14
J 0
(-8275 4175);
DISPLAY 1.021277 (-8275 4175);
DISPLAY INVISIBLE (-8275 4175);
FORCEADD GND..1
(-2200 1875);
FORCEPROP 3 LASTPIN (-2200 1925) SIG_NAME GND\g
J 0
(-2190 1935);
DISPLAY 0.659574 (-2190 1935);
PAINT MONO (-2190 1935);
DISPLAY INVISIBLE (-2190 1935);
FORCEPROP 1 LAST VOLTAGE 0.0
J 0
(-2245 1832);
DISPLAY 0.723404 (-2245 1832);
PAINT SKYBLUE (-2245 1832);
DISPLAY INVISIBLE (-2245 1832);
FORCEPROP 2 LAST CDS_LIB mstr_symbols
J 0
(-2200 1875);
DISPLAY 0.723404 (-2200 1875);
DISPLAY INVISIBLE (-2200 1875);
FORCEPROP 1 LAST SIZE 1B
J 0
(-2125 1825);
DISPLAY 0.851064 (-2125 1825);
PAINT GREEN (-2125 1825);
DISPLAY INVISIBLE (-2125 1825);
FORCEPROP 1 LAST BODY_TYPE PLUMBING
J 0
(-2245 1832);
DISPLAY 0.340426 (-2245 1832);
PAINT GREEN (-2245 1832);
DISPLAY INVISIBLE (-2245 1832);
FORCEPROP 1 LAST HDL_POWER GND
J 0
(-2200 2025);
DISPLAY 0.851064 (-2200 2025);
PAINT GREEN (-2200 2025);
DISPLAY INVISIBLE (-2200 2025);
FORCEPROP 1 LAST PATH I140
J 0
(-2125 1875);
DISPLAY 0.872340 (-2125 1875);
PAINT AQUA (-2125 1875);
DISPLAY INVISIBLE (-2125 1875);
FORCEADD GND..1
(-400 1650);
FORCEPROP 3 LASTPIN (-400 1700) SIG_NAME GND\g
J 0
(-390 1710);
DISPLAY 0.659574 (-390 1710);
PAINT MONO (-390 1710);
DISPLAY INVISIBLE (-390 1710);
FORCEPROP 1 LAST VOLTAGE 0.0
J 0
(-445 1607);
DISPLAY 0.723404 (-445 1607);
PAINT SKYBLUE (-445 1607);
DISPLAY INVISIBLE (-445 1607);
FORCEPROP 2 LAST CDS_LIB mstr_symbols
J 0
(-400 1650);
DISPLAY 0.723404 (-400 1650);
DISPLAY INVISIBLE (-400 1650);
FORCEPROP 1 LAST SIZE 1B
J 0
(-325 1600);
DISPLAY 0.851064 (-325 1600);
PAINT GREEN (-325 1600);
DISPLAY INVISIBLE (-325 1600);
FORCEPROP 1 LAST BODY_TYPE PLUMBING
J 0
(-445 1607);
DISPLAY 0.340426 (-445 1607);
PAINT GREEN (-445 1607);
DISPLAY INVISIBLE (-445 1607);
FORCEPROP 1 LAST HDL_POWER GND
J 0
(-400 1800);
DISPLAY 0.851064 (-400 1800);
PAINT GREEN (-400 1800);
DISPLAY INVISIBLE (-400 1800);
FORCEPROP 1 LAST PATH I141
J 0
(-325 1650);
DISPLAY 0.872340 (-325 1650);
PAINT AQUA (-325 1650);
DISPLAY INVISIBLE (-325 1650);
FORCEADD OFFPAGE..1
(-8325 4200);
FORCEPROP 2 LAST $XR0 17 
J 0
(-8546 4200);
DISPLAY 0.638298 (-8546 4200);
PAINT MONO (-8546 4200);
FORCEPROP 2 LAST CDS_LIB mstr_standard
J 0
(-8325 4200);
DISPLAY 0.808511 (-8325 4200);
DISPLAY INVISIBLE (-8325 4200);
FORCEPROP 1 LAST OFFPAGE TRUE
J 0
(-8000 4075);
DISPLAY 0.872340 (-8000 4075);
PAINT GREEN (-8000 4075);
DISPLAY INVISIBLE (-8000 4075);
FORCEPROP 1 LAST COMMENT_BODY TRUE
J 0
(-8200 4100);
DISPLAY 0.872340 (-8200 4100);
PAINT GREEN (-8200 4100);
DISPLAY INVISIBLE (-8200 4100);
FORCEPROP 2 LAST PATH I15
J 0
(-8275 4275);
DISPLAY 1.021277 (-8275 4275);
DISPLAY INVISIBLE (-8275 4275);
FORCEADD OFFPAGE..1
(-8325 4500);
FORCEPROP 2 LAST $XR0 17 
J 0
(-8546 4500);
DISPLAY 0.638298 (-8546 4500);
PAINT MONO (-8546 4500);
FORCEPROP 2 LAST CDS_LIB mstr_standard
J 0
(-8325 4500);
DISPLAY 0.808511 (-8325 4500);
DISPLAY INVISIBLE (-8325 4500);
FORCEPROP 1 LAST OFFPAGE TRUE
J 0
(-8000 4375);
DISPLAY 0.872340 (-8000 4375);
PAINT GREEN (-8000 4375);
DISPLAY INVISIBLE (-8000 4375);
FORCEPROP 1 LAST COMMENT_BODY TRUE
J 0
(-8200 4400);
DISPLAY 0.872340 (-8200 4400);
PAINT GREEN (-8200 4400);
DISPLAY INVISIBLE (-8200 4400);
FORCEPROP 2 LAST PATH I16
J 0
(-8275 4575);
DISPLAY 1.021277 (-8275 4575);
DISPLAY INVISIBLE (-8275 4575);
FORCEADD OFFPAGE..1
(-8325 4400);
FORCEPROP 2 LAST $XR0 17 
J 0
(-8546 4400);
DISPLAY 0.638298 (-8546 4400);
PAINT MONO (-8546 4400);
FORCEPROP 2 LAST CDS_LIB mstr_standard
J 0
(-8325 4400);
DISPLAY 0.723404 (-8325 4400);
PAINT MONO (-8325 4400);
DISPLAY INVISIBLE (-8325 4400);
FORCEPROP 1 LAST OFFPAGE TRUE
J 0
(-8000 4275);
DISPLAY 0.872340 (-8000 4275);
PAINT GREEN (-8000 4275);
DISPLAY INVISIBLE (-8000 4275);
FORCEPROP 1 LAST COMMENT_BODY TRUE
J 0
(-8200 4300);
DISPLAY 0.872340 (-8200 4300);
PAINT GREEN (-8200 4300);
DISPLAY INVISIBLE (-8200 4300);
FORCEPROP 2 LAST PATH I17
J 0
(-8275 4475);
DISPLAY 1.021277 (-8275 4475);
DISPLAY INVISIBLE (-8275 4475);
FORCEADD SCONN288_DDR506112002KQ..3
(-1300 3650);
FORCEPROP 1 LAST LOCATION J69
J 0
(-1750 5625);
DISPLAY 0.468085 (-1750 5625);
PAINT SKYBLUE (-1750 5625);
FORCEPROP 0 LAST $SEC 3
J 0
(-1750 5775);
DISPLAY 0.680851 (-1750 5775);
PAINT MONO (-1750 5775);
DISPLAY INVISIBLE (-1750 5775);
FORCEPROP 2 LAST CDS_SEC 3
J 0
(-1750 5775);
DISPLAY 1.021277 (-1750 5775);
DISPLAY INVISIBLE (-1750 5775);
FORCEPROP 0 LASTPIN (-700 2050) $PN G1
J 0
(-690 2060);
DISPLAY 0.680851 (-690 2060);
PAINT MONO (-690 2060);
FORCEPROP 0 LASTPIN (-700 2000) $PN G2
J 0
(-690 2010);
DISPLAY 0.680851 (-690 2010);
PAINT MONO (-690 2010);
FORCEPROP 0 LASTPIN (-700 1950) $PN G3
J 0
(-690 1960);
DISPLAY 0.680851 (-690 1960);
PAINT MONO (-690 1960);
FORCEPROP 0 LASTPIN (-1900 5200) $PN 1
J 2
(-1910 5210);
DISPLAY 0.680851 (-1910 5210);
PAINT MONO (-1910 5210);
FORCEPROP 0 LASTPIN (-1900 5250) $PN 145
J 2
(-1910 5260);
DISPLAY 0.680851 (-1910 5260);
PAINT MONO (-1910 5260);
FORCEPROP 0 LASTPIN (-1900 5300) $PN 146
J 2
(-1910 5310);
DISPLAY 0.680851 (-1910 5310);
PAINT MONO (-1910 5310);
FORCEPROP 0 LASTPIN (-700 2150) $PN 6
J 0
(-690 2160);
DISPLAY 0.680851 (-690 2160);
PAINT MONO (-690 2160);
FORCEPROP 0 LASTPIN (-700 2200) $PN 8
J 0
(-690 2210);
DISPLAY 0.680851 (-690 2210);
PAINT MONO (-690 2210);
FORCEPROP 0 LASTPIN (-700 2250) $PN 10
J 0
(-690 2260);
DISPLAY 0.680851 (-690 2260);
PAINT MONO (-690 2260);
FORCEPROP 0 LASTPIN (-700 2300) $PN 13
J 0
(-690 2310);
DISPLAY 0.680851 (-690 2310);
PAINT MONO (-690 2310);
FORCEPROP 0 LASTPIN (-700 2350) $PN 15
J 0
(-690 2360);
DISPLAY 0.680851 (-690 2360);
PAINT MONO (-690 2360);
FORCEPROP 0 LASTPIN (-700 2400) $PN 17
J 0
(-690 2410);
DISPLAY 0.680851 (-690 2410);
PAINT MONO (-690 2410);
FORCEPROP 0 LASTPIN (-700 2450) $PN 19
J 0
(-690 2460);
DISPLAY 0.680851 (-690 2460);
PAINT MONO (-690 2460);
FORCEPROP 0 LASTPIN (-700 2500) $PN 21
J 0
(-690 2510);
DISPLAY 0.680851 (-690 2510);
PAINT MONO (-690 2510);
FORCEPROP 0 LASTPIN (-700 2550) $PN 24
J 0
(-690 2560);
DISPLAY 0.680851 (-690 2560);
PAINT MONO (-690 2560);
FORCEPROP 0 LASTPIN (-700 2600) $PN 26
J 0
(-690 2610);
DISPLAY 0.680851 (-690 2610);
PAINT MONO (-690 2610);
FORCEPROP 0 LASTPIN (-700 2650) $PN 28
J 0
(-690 2660);
DISPLAY 0.680851 (-690 2660);
PAINT MONO (-690 2660);
FORCEPROP 0 LASTPIN (-700 2700) $PN 30
J 0
(-690 2710);
DISPLAY 0.680851 (-690 2710);
PAINT MONO (-690 2710);
FORCEPROP 0 LASTPIN (-700 2750) $PN 32
J 0
(-690 2760);
DISPLAY 0.680851 (-690 2760);
PAINT MONO (-690 2760);
FORCEPROP 0 LASTPIN (-700 2800) $PN 35
J 0
(-690 2810);
DISPLAY 0.680851 (-690 2810);
PAINT MONO (-690 2810);
FORCEPROP 0 LASTPIN (-700 2850) $PN 37
J 0
(-690 2860);
DISPLAY 0.680851 (-690 2860);
PAINT MONO (-690 2860);
FORCEPROP 0 LASTPIN (-700 2900) $PN 39
J 0
(-690 2910);
DISPLAY 0.680851 (-690 2910);
PAINT MONO (-690 2910);
FORCEPROP 0 LASTPIN (-700 2950) $PN 41
J 0
(-690 2960);
DISPLAY 0.680851 (-690 2960);
PAINT MONO (-690 2960);
FORCEPROP 0 LASTPIN (-700 3000) $PN 43
J 0
(-690 3010);
DISPLAY 0.680851 (-690 3010);
PAINT MONO (-690 3010);
FORCEPROP 0 LASTPIN (-700 3050) $PN 46
J 0
(-690 3060);
DISPLAY 0.680851 (-690 3060);
PAINT MONO (-690 3060);
FORCEPROP 0 LASTPIN (-700 3100) $PN 48
J 0
(-690 3110);
DISPLAY 0.680851 (-690 3110);
PAINT MONO (-690 3110);
FORCEPROP 0 LASTPIN (-700 3150) $PN 50
J 0
(-690 3160);
DISPLAY 0.680851 (-690 3160);
PAINT MONO (-690 3160);
FORCEPROP 0 LASTPIN (-700 3200) $PN 52
J 0
(-690 3210);
DISPLAY 0.680851 (-690 3210);
PAINT MONO (-690 3210);
FORCEPROP 0 LASTPIN (-700 3250) $PN 54
J 0
(-690 3260);
DISPLAY 0.680851 (-690 3260);
PAINT MONO (-690 3260);
FORCEPROP 0 LASTPIN (-700 3300) $PN 57
J 0
(-690 3310);
DISPLAY 0.680851 (-690 3310);
PAINT MONO (-690 3310);
FORCEPROP 0 LASTPIN (-700 3350) $PN 59
J 0
(-690 3360);
DISPLAY 0.680851 (-690 3360);
PAINT MONO (-690 3360);
FORCEPROP 0 LASTPIN (-700 3400) $PN 61
J 0
(-690 3410);
DISPLAY 0.680851 (-690 3410);
PAINT MONO (-690 3410);
FORCEPROP 0 LASTPIN (-700 3450) $PN 63
J 0
(-690 3460);
DISPLAY 0.680851 (-690 3460);
PAINT MONO (-690 3460);
FORCEPROP 0 LASTPIN (-700 3500) $PN 65
J 0
(-690 3510);
DISPLAY 0.680851 (-690 3510);
PAINT MONO (-690 3510);
FORCEPROP 0 LASTPIN (-700 3550) $PN 67
J 0
(-690 3560);
DISPLAY 0.680851 (-690 3560);
PAINT MONO (-690 3560);
FORCEPROP 0 LASTPIN (-700 3600) $PN 69
J 0
(-690 3610);
DISPLAY 0.680851 (-690 3610);
PAINT MONO (-690 3610);
FORCEPROP 0 LASTPIN (-700 3650) $PN 71
J 0
(-690 3660);
DISPLAY 0.680851 (-690 3660);
PAINT MONO (-690 3660);
FORCEPROP 0 LASTPIN (-700 3700) $PN 73
J 0
(-690 3710);
DISPLAY 0.680851 (-690 3710);
PAINT MONO (-690 3710);
FORCEPROP 0 LASTPIN (-700 3750) $PN 75
J 0
(-690 3760);
DISPLAY 0.680851 (-690 3760);
PAINT MONO (-690 3760);
FORCEPROP 0 LASTPIN (-700 3800) $PN 77
J 0
(-690 3810);
DISPLAY 0.680851 (-690 3810);
PAINT MONO (-690 3810);
FORCEPROP 0 LASTPIN (-700 3850) $PN 79
J 0
(-690 3860);
DISPLAY 0.680851 (-690 3860);
PAINT MONO (-690 3860);
FORCEPROP 0 LASTPIN (-700 3900) $PN 81
J 0
(-690 3910);
DISPLAY 0.680851 (-690 3910);
PAINT MONO (-690 3910);
FORCEPROP 0 LASTPIN (-700 3950) $PN 83
J 0
(-690 3960);
DISPLAY 0.680851 (-690 3960);
PAINT MONO (-690 3960);
FORCEPROP 0 LASTPIN (-700 4000) $PN 85
J 0
(-690 4010);
DISPLAY 0.680851 (-690 4010);
PAINT MONO (-690 4010);
FORCEPROP 0 LASTPIN (-700 4050) $PN 88
J 0
(-690 4060);
DISPLAY 0.680851 (-690 4060);
PAINT MONO (-690 4060);
FORCEPROP 0 LASTPIN (-700 4100) $PN 90
J 0
(-690 4110);
DISPLAY 0.680851 (-690 4110);
PAINT MONO (-690 4110);
FORCEPROP 0 LASTPIN (-700 4150) $PN 92
J 0
(-690 4160);
DISPLAY 0.680851 (-690 4160);
PAINT MONO (-690 4160);
FORCEPROP 0 LASTPIN (-700 4200) $PN 95
J 0
(-690 4210);
DISPLAY 0.680851 (-690 4210);
PAINT MONO (-690 4210);
FORCEPROP 0 LASTPIN (-700 4250) $PN 97
J 0
(-690 4260);
DISPLAY 0.680851 (-690 4260);
PAINT MONO (-690 4260);
FORCEPROP 0 LASTPIN (-700 4300) $PN 99
J 0
(-690 4310);
DISPLAY 0.680851 (-690 4310);
PAINT MONO (-690 4310);
FORCEPROP 0 LASTPIN (-700 4350) $PN 101
J 0
(-690 4360);
DISPLAY 0.680851 (-690 4360);
PAINT MONO (-690 4360);
FORCEPROP 0 LASTPIN (-700 4400) $PN 103
J 0
(-690 4410);
DISPLAY 0.680851 (-690 4410);
PAINT MONO (-690 4410);
FORCEPROP 0 LASTPIN (-700 4450) $PN 106
J 0
(-690 4460);
DISPLAY 0.680851 (-690 4460);
PAINT MONO (-690 4460);
FORCEPROP 0 LASTPIN (-700 4500) $PN 108
J 0
(-690 4510);
DISPLAY 0.680851 (-690 4510);
PAINT MONO (-690 4510);
FORCEPROP 0 LASTPIN (-700 4550) $PN 110
J 0
(-690 4560);
DISPLAY 0.680851 (-690 4560);
PAINT MONO (-690 4560);
FORCEPROP 0 LASTPIN (-700 4600) $PN 112
J 0
(-690 4610);
DISPLAY 0.680851 (-690 4610);
PAINT MONO (-690 4610);
FORCEPROP 0 LASTPIN (-700 4650) $PN 114
J 0
(-690 4660);
DISPLAY 0.680851 (-690 4660);
PAINT MONO (-690 4660);
FORCEPROP 0 LASTPIN (-700 4700) $PN 117
J 0
(-690 4710);
DISPLAY 0.680851 (-690 4710);
PAINT MONO (-690 4710);
FORCEPROP 0 LASTPIN (-700 4750) $PN 119
J 0
(-690 4760);
DISPLAY 0.680851 (-690 4760);
PAINT MONO (-690 4760);
FORCEPROP 0 LASTPIN (-700 4800) $PN 121
J 0
(-690 4810);
DISPLAY 0.680851 (-690 4810);
PAINT MONO (-690 4810);
FORCEPROP 0 LASTPIN (-700 4850) $PN 123
J 0
(-690 4860);
DISPLAY 0.680851 (-690 4860);
PAINT MONO (-690 4860);
FORCEPROP 0 LASTPIN (-700 4900) $PN 125
J 0
(-690 4910);
DISPLAY 0.680851 (-690 4910);
PAINT MONO (-690 4910);
FORCEPROP 0 LASTPIN (-700 4950) $PN 128
J 0
(-690 4960);
DISPLAY 0.680851 (-690 4960);
PAINT MONO (-690 4960);
FORCEPROP 0 LASTPIN (-700 5000) $PN 130
J 0
(-690 5010);
DISPLAY 0.680851 (-690 5010);
PAINT MONO (-690 5010);
FORCEPROP 0 LASTPIN (-700 5050) $PN 132
J 0
(-690 5060);
DISPLAY 0.680851 (-690 5060);
PAINT MONO (-690 5060);
FORCEPROP 0 LASTPIN (-700 5100) $PN 134
J 0
(-690 5110);
DISPLAY 0.680851 (-690 5110);
PAINT MONO (-690 5110);
FORCEPROP 0 LASTPIN (-700 5150) $PN 136
J 0
(-690 5160);
DISPLAY 0.680851 (-690 5160);
PAINT MONO (-690 5160);
FORCEPROP 0 LASTPIN (-700 5200) $PN 139
J 0
(-690 5210);
DISPLAY 0.680851 (-690 5210);
PAINT MONO (-690 5210);
FORCEPROP 0 LASTPIN (-700 5250) $PN 141
J 0
(-690 5260);
DISPLAY 0.680851 (-690 5260);
PAINT MONO (-690 5260);
FORCEPROP 0 LASTPIN (-700 5300) $PN 143
J 0
(-690 5310);
DISPLAY 0.680851 (-690 5310);
PAINT MONO (-690 5310);
FORCEPROP 0 LASTPIN (-1900 2050) $PN 151
J 2
(-1910 2060);
DISPLAY 0.680851 (-1910 2060);
PAINT MONO (-1910 2060);
FORCEPROP 0 LASTPIN (-1900 2100) $PN 153
J 2
(-1910 2110);
DISPLAY 0.680851 (-1910 2110);
PAINT MONO (-1910 2110);
FORCEPROP 0 LASTPIN (-1900 2150) $PN 155
J 2
(-1910 2160);
DISPLAY 0.680851 (-1910 2160);
PAINT MONO (-1910 2160);
FORCEPROP 0 LASTPIN (-1900 2200) $PN 158
J 2
(-1910 2210);
DISPLAY 0.680851 (-1910 2210);
PAINT MONO (-1910 2210);
FORCEPROP 0 LASTPIN (-1900 2250) $PN 160
J 2
(-1910 2260);
DISPLAY 0.680851 (-1910 2260);
PAINT MONO (-1910 2260);
FORCEPROP 0 LASTPIN (-1900 2300) $PN 162
J 2
(-1910 2310);
DISPLAY 0.680851 (-1910 2310);
PAINT MONO (-1910 2310);
FORCEPROP 0 LASTPIN (-1900 2350) $PN 164
J 2
(-1910 2360);
DISPLAY 0.680851 (-1910 2360);
PAINT MONO (-1910 2360);
FORCEPROP 0 LASTPIN (-1900 2400) $PN 166
J 2
(-1910 2410);
DISPLAY 0.680851 (-1910 2410);
PAINT MONO (-1910 2410);
FORCEPROP 0 LASTPIN (-1900 2450) $PN 169
J 2
(-1910 2460);
DISPLAY 0.680851 (-1910 2460);
PAINT MONO (-1910 2460);
FORCEPROP 0 LASTPIN (-1900 2500) $PN 171
J 2
(-1910 2510);
DISPLAY 0.680851 (-1910 2510);
PAINT MONO (-1910 2510);
FORCEPROP 0 LASTPIN (-1900 2550) $PN 173
J 2
(-1910 2560);
DISPLAY 0.680851 (-1910 2560);
PAINT MONO (-1910 2560);
FORCEPROP 0 LASTPIN (-1900 2600) $PN 175
J 2
(-1910 2610);
DISPLAY 0.680851 (-1910 2610);
PAINT MONO (-1910 2610);
FORCEPROP 0 LASTPIN (-1900 2650) $PN 177
J 2
(-1910 2660);
DISPLAY 0.680851 (-1910 2660);
PAINT MONO (-1910 2660);
FORCEPROP 0 LASTPIN (-1900 2700) $PN 180
J 2
(-1910 2710);
DISPLAY 0.680851 (-1910 2710);
PAINT MONO (-1910 2710);
FORCEPROP 0 LASTPIN (-1900 2750) $PN 182
J 2
(-1910 2760);
DISPLAY 0.680851 (-1910 2760);
PAINT MONO (-1910 2760);
FORCEPROP 0 LASTPIN (-1900 2800) $PN 184
J 2
(-1910 2810);
DISPLAY 0.680851 (-1910 2810);
PAINT MONO (-1910 2810);
FORCEPROP 0 LASTPIN (-1900 2850) $PN 186
J 2
(-1910 2860);
DISPLAY 0.680851 (-1910 2860);
PAINT MONO (-1910 2860);
FORCEPROP 0 LASTPIN (-1900 2900) $PN 188
J 2
(-1910 2910);
DISPLAY 0.680851 (-1910 2910);
PAINT MONO (-1910 2910);
FORCEPROP 0 LASTPIN (-1900 2950) $PN 191
J 2
(-1910 2960);
DISPLAY 0.680851 (-1910 2960);
PAINT MONO (-1910 2960);
FORCEPROP 0 LASTPIN (-1900 3000) $PN 193
J 2
(-1910 3010);
DISPLAY 0.680851 (-1910 3010);
PAINT MONO (-1910 3010);
FORCEPROP 0 LASTPIN (-1900 3050) $PN 195
J 2
(-1910 3060);
DISPLAY 0.680851 (-1910 3060);
PAINT MONO (-1910 3060);
FORCEPROP 0 LASTPIN (-1900 3100) $PN 197
J 2
(-1910 3110);
DISPLAY 0.680851 (-1910 3110);
PAINT MONO (-1910 3110);
FORCEPROP 0 LASTPIN (-1900 3150) $PN 199
J 2
(-1910 3160);
DISPLAY 0.680851 (-1910 3160);
PAINT MONO (-1910 3160);
FORCEPROP 0 LASTPIN (-1900 3200) $PN 202
J 2
(-1910 3210);
DISPLAY 0.680851 (-1910 3210);
PAINT MONO (-1910 3210);
FORCEPROP 0 LASTPIN (-1900 3250) $PN 204
J 2
(-1910 3260);
DISPLAY 0.680851 (-1910 3260);
PAINT MONO (-1910 3260);
FORCEPROP 0 LASTPIN (-1900 3300) $PN 206
J 2
(-1910 3310);
DISPLAY 0.680851 (-1910 3310);
PAINT MONO (-1910 3310);
FORCEPROP 0 LASTPIN (-1900 3350) $PN 208
J 2
(-1910 3360);
DISPLAY 0.680851 (-1910 3360);
PAINT MONO (-1910 3360);
FORCEPROP 0 LASTPIN (-1900 3400) $PN 210
J 2
(-1910 3410);
DISPLAY 0.680851 (-1910 3410);
PAINT MONO (-1910 3410);
FORCEPROP 0 LASTPIN (-1900 3450) $PN 212
J 2
(-1910 3460);
DISPLAY 0.680851 (-1910 3460);
PAINT MONO (-1910 3460);
FORCEPROP 0 LASTPIN (-1900 3500) $PN 214
J 2
(-1910 3510);
DISPLAY 0.680851 (-1910 3510);
PAINT MONO (-1910 3510);
FORCEPROP 0 LASTPIN (-1900 3550) $PN 216
J 2
(-1910 3560);
DISPLAY 0.680851 (-1910 3560);
PAINT MONO (-1910 3560);
FORCEPROP 0 LASTPIN (-1900 3600) $PN 219
J 2
(-1910 3610);
DISPLAY 0.680851 (-1910 3610);
PAINT MONO (-1910 3610);
FORCEPROP 0 LASTPIN (-1900 3650) $PN 222
J 2
(-1910 3660);
DISPLAY 0.680851 (-1910 3660);
PAINT MONO (-1910 3660);
FORCEPROP 0 LASTPIN (-1900 3700) $PN 224
J 2
(-1910 3710);
DISPLAY 0.680851 (-1910 3710);
PAINT MONO (-1910 3710);
FORCEPROP 0 LASTPIN (-1900 3750) $PN 226
J 2
(-1910 3760);
DISPLAY 0.680851 (-1910 3760);
PAINT MONO (-1910 3760);
FORCEPROP 0 LASTPIN (-1900 3800) $PN 228
J 2
(-1910 3810);
DISPLAY 0.680851 (-1910 3810);
PAINT MONO (-1910 3810);
FORCEPROP 0 LASTPIN (-1900 3850) $PN 230
J 2
(-1910 3860);
DISPLAY 0.680851 (-1910 3860);
PAINT MONO (-1910 3860);
FORCEPROP 0 LASTPIN (-1900 3900) $PN 233
J 2
(-1910 3910);
DISPLAY 0.680851 (-1910 3910);
PAINT MONO (-1910 3910);
FORCEPROP 0 LASTPIN (-1900 3950) $PN 235
J 2
(-1910 3960);
DISPLAY 0.680851 (-1910 3960);
PAINT MONO (-1910 3960);
FORCEPROP 0 LASTPIN (-1900 4000) $PN 237
J 2
(-1910 4010);
DISPLAY 0.680851 (-1910 4010);
PAINT MONO (-1910 4010);
FORCEPROP 0 LASTPIN (-1900 4050) $PN 240
J 2
(-1910 4060);
DISPLAY 0.680851 (-1910 4060);
PAINT MONO (-1910 4060);
FORCEPROP 0 LASTPIN (-1900 4100) $PN 242
J 2
(-1910 4110);
DISPLAY 0.680851 (-1910 4110);
PAINT MONO (-1910 4110);
FORCEPROP 0 LASTPIN (-1900 4150) $PN 244
J 2
(-1910 4160);
DISPLAY 0.680851 (-1910 4160);
PAINT MONO (-1910 4160);
FORCEPROP 0 LASTPIN (-1900 4200) $PN 246
J 2
(-1910 4210);
DISPLAY 0.680851 (-1910 4210);
PAINT MONO (-1910 4210);
FORCEPROP 0 LASTPIN (-1900 4250) $PN 248
J 2
(-1910 4260);
DISPLAY 0.680851 (-1910 4260);
PAINT MONO (-1910 4260);
FORCEPROP 0 LASTPIN (-1900 4300) $PN 251
J 2
(-1910 4310);
DISPLAY 0.680851 (-1910 4310);
PAINT MONO (-1910 4310);
FORCEPROP 0 LASTPIN (-1900 4350) $PN 253
J 2
(-1910 4360);
DISPLAY 0.680851 (-1910 4360);
PAINT MONO (-1910 4360);
FORCEPROP 0 LASTPIN (-1900 4400) $PN 255
J 2
(-1910 4410);
DISPLAY 0.680851 (-1910 4410);
PAINT MONO (-1910 4410);
FORCEPROP 0 LASTPIN (-1900 4450) $PN 257
J 2
(-1910 4460);
DISPLAY 0.680851 (-1910 4460);
PAINT MONO (-1910 4460);
FORCEPROP 0 LASTPIN (-1900 4500) $PN 259
J 2
(-1910 4510);
DISPLAY 0.680851 (-1910 4510);
PAINT MONO (-1910 4510);
FORCEPROP 0 LASTPIN (-1900 4550) $PN 262
J 2
(-1910 4560);
DISPLAY 0.680851 (-1910 4560);
PAINT MONO (-1910 4560);
FORCEPROP 0 LASTPIN (-1900 4600) $PN 264
J 2
(-1910 4610);
DISPLAY 0.680851 (-1910 4610);
PAINT MONO (-1910 4610);
FORCEPROP 0 LASTPIN (-1900 4650) $PN 266
J 2
(-1910 4660);
DISPLAY 0.680851 (-1910 4660);
PAINT MONO (-1910 4660);
FORCEPROP 0 LASTPIN (-1900 4700) $PN 268
J 2
(-1910 4710);
DISPLAY 0.680851 (-1910 4710);
PAINT MONO (-1910 4710);
FORCEPROP 0 LASTPIN (-1900 4750) $PN 270
J 2
(-1910 4760);
DISPLAY 0.680851 (-1910 4760);
PAINT MONO (-1910 4760);
FORCEPROP 0 LASTPIN (-1900 4800) $PN 273
J 2
(-1910 4810);
DISPLAY 0.680851 (-1910 4810);
PAINT MONO (-1910 4810);
FORCEPROP 0 LASTPIN (-1900 4850) $PN 275
J 2
(-1910 4860);
DISPLAY 0.680851 (-1910 4860);
PAINT MONO (-1910 4860);
FORCEPROP 0 LASTPIN (-1900 4900) $PN 277
J 2
(-1910 4910);
DISPLAY 0.680851 (-1910 4910);
PAINT MONO (-1910 4910);
FORCEPROP 0 LASTPIN (-1900 4950) $PN 279
J 2
(-1910 4960);
DISPLAY 0.680851 (-1910 4960);
PAINT MONO (-1910 4960);
FORCEPROP 0 LASTPIN (-1900 5000) $PN 281
J 2
(-1910 5010);
DISPLAY 0.680851 (-1910 5010);
PAINT MONO (-1910 5010);
FORCEPROP 0 LASTPIN (-1900 5050) $PN 284
J 2
(-1910 5060);
DISPLAY 0.680851 (-1910 5060);
PAINT MONO (-1910 5060);
FORCEPROP 0 LASTPIN (-1900 5100) $PN 286
J 2
(-1910 5110);
DISPLAY 0.680851 (-1910 5110);
PAINT MONO (-1910 5110);
FORCEPROP 0 LASTPIN (-1900 5150) $PN 288
J 2
(-1910 5160);
DISPLAY 0.680851 (-1910 5160);
PAINT MONO (-1910 5160);
FORCEPROP 2 LAST VALUE SCONN288_DDR506112002KQ
J 0
(-1750 5675);
DISPLAY 0.489362 (-1750 5675);
PAINT SKYBLUE (-1750 5675);
FORCEPROP 1 LAST MATERIAL IO
J 0
(-1750 5475);
DISPLAY 0.468085 (-1750 5475);
PAINT SKYBLUE (-1750 5475);
FORCEPROP 2 LAST PART_TYPE SMLF
J 0
(-1750 5725);
DISPLAY 1.021277 (-1750 5725);
FORCEPROP 2 LAST CDS_LIB pure_quanta
J 0
(-1300 3650);
DISPLAY INVISIBLE (-1300 3650);
FORCEPROP 1 LAST NEEDS_NO_SIZE TRUE
J 0
(-1300 3650);
DISPLAY 0.723404 (-1300 3650);
PAINT GREEN (-1300 3650);
DISPLAY INVISIBLE (-1300 3650);
FORCEPROP 1 LAST CDS_LMAN_SYM_OUTLINE -450,1800,450,-1750
J 0
(-1300 3650);
DISPLAY 0.468085 (-1300 3650);
PAINT GREEN (-1300 3650);
DISPLAY INVISIBLE (-1300 3650);
FORCEPROP 1 LAST PATH I177
J 0
(-1300 3650);
DISPLAY 0.723404 (-1300 3650);
PAINT GREEN (-1300 3650);
DISPLAY INVISIBLE (-1300 3650);
FORCEPROP 1 LAST PART_NUMBER DFHST8FS479
J 0
(-1750 5550);
DISPLAY 0.468085 (-1750 5550);
PAINT SKYBLUE (-1750 5550);
DISPLAY INVISIBLE (-1750 5550);
FORCEADD OFFPAGE..5
(-8175 3000);
FORCEPROP 2 LAST $XR0 17 
J 0
(-8429 3000);
DISPLAY 0.638298 (-8429 3000);
PAINT MONO (-8429 3000);
FORCEPROP 2 LAST CDS_LIB mstr_standard
J 0
(-8175 3000);
DISPLAY INVISIBLE (-8175 3000);
FORCEPROP 1 LAST OFFPAGE TRUE
J 0
(-7850 2875);
DISPLAY 0.872340 (-7850 2875);
PAINT GREEN (-7850 2875);
DISPLAY INVISIBLE (-7850 2875);
FORCEPROP 1 LAST COMMENT_BODY TRUE
J 0
(-8075 2925);
DISPLAY 0.872340 (-8075 2925);
PAINT GREEN (-8075 2925);
DISPLAY INVISIBLE (-8075 2925);
FORCEPROP 2 LAST PATH I178
J 0
(-8125 3075);
DISPLAY 1.021277 (-8125 3075);
DISPLAY INVISIBLE (-8125 3075);
FORCEADD OFFPAGE..1
(-8325 4350);
FORCEPROP 2 LAST $XR0 17 
J 0
(-8546 4350);
DISPLAY 0.638298 (-8546 4350);
PAINT MONO (-8546 4350);
FORCEPROP 2 LAST CDS_LIB mstr_standard
J 0
(-8325 4350);
DISPLAY 0.808511 (-8325 4350);
DISPLAY INVISIBLE (-8325 4350);
FORCEPROP 1 LAST OFFPAGE TRUE
J 0
(-8000 4225);
DISPLAY 0.872340 (-8000 4225);
PAINT GREEN (-8000 4225);
DISPLAY INVISIBLE (-8000 4225);
FORCEPROP 1 LAST COMMENT_BODY TRUE
J 0
(-8200 4250);
DISPLAY 0.872340 (-8200 4250);
PAINT GREEN (-8200 4250);
DISPLAY INVISIBLE (-8200 4250);
FORCEPROP 2 LAST PATH I18
J 0
(-8275 4425);
DISPLAY 1.021277 (-8275 4425);
DISPLAY INVISIBLE (-8275 4425);
FORCEADD Q_CAP..1
R 2
(-8650 3175);
FORCEPROP 1 LAST LOCATION C116
J 2
(-8700 3275);
DISPLAY 0.489362 (-8700 3275);
PAINT SKYBLUE (-8700 3275);
FORCEPROP 0 LAST $SEC 1
J 0
(-8700 3325);
DISPLAY 0.680851 (-8700 3325);
PAINT MONO (-8700 3325);
DISPLAY INVISIBLE (-8700 3325);
FORCEPROP 0 LAST CDS_SEC 1
J 0
(-8700 3325);
DISPLAY 1.021277 (-8700 3325);
DISPLAY INVISIBLE (-8700 3325);
FORCEPROP 1 LASTPIN (-8650 3275) $PN 1
J 2
(-8660 3255);
DISPLAY 0.489362 (-8660 3255);
PAINT MONO (-8660 3255);
FORCEPROP 1 LASTPIN (-8650 3075) $PN 2
J 2
(-8660 3055);
DISPLAY 0.489362 (-8660 3055);
PAINT MONO (-8660 3055);
FORCEPROP 1 LAST PACK_TYPE 0402
J 2
(-8700 2975);
DISPLAY 0.489362 (-8700 2975);
PAINT SKYBLUE (-8700 2975);
FORCEPROP 1 LAST MATERIAL X7R
J 2
(-8700 3075);
DISPLAY 0.489362 (-8700 3075);
PAINT SKYBLUE (-8700 3075);
FORCEPROP 1 LAST TOLERANCE 10%
J 2
(-8700 3125);
DISPLAY 0.489362 (-8700 3125);
PAINT SKYBLUE (-8700 3125);
FORCEPROP 1 LAST VALUE 0.1UF
J 2
(-8700 3225);
DISPLAY 0.489362 (-8700 3225);
PAINT SKYBLUE (-8700 3225);
FORCEPROP 1 LAST VOLTAGE 25V
J 2
(-8700 3175);
DISPLAY 0.489362 (-8700 3175);
PAINT SKYBLUE (-8700 3175);
FORCEPROP 0 LAST BOM_COST MEM
J 2
(-8705 3320);
DISPLAY 0.595745 (-8705 3320);
PAINT MONO (-8705 3320);
DISPLAY INVISIBLE (-8705 3320);
FORCEPROP 2 LAST CDS_LIB pure_quanta
J 0
(-8650 3175);
DISPLAY INVISIBLE (-8650 3175);
FORCEPROP 2 LAST ROOM 
J 2
(-8705 3320);
DISPLAY 0.595745 (-8705 3320);
PAINT RED (-8705 3320);
DISPLAY INVISIBLE (-8705 3320);
FORCEPROP 1 LAST PATH I186
J 2
(-8700 3325);
DISPLAY 0.978723 (-8700 3325);
PAINT WHITE (-8700 3325);
DISPLAY INVISIBLE (-8700 3325);
FORCEPROP 1 LAST PART_NUMBER CH4104K1B00
J 2
(-8700 3025);
DISPLAY 0.489362 (-8700 3025);
PAINT SKYBLUE (-8700 3025);
DISPLAY INVISIBLE (-8700 3025);
FORCEADD GND..1
(-8650 2950);
FORCEPROP 3 LASTPIN (-8650 3000) SIG_NAME GND\g
J 0
(-8640 3010);
DISPLAY 0.659574 (-8640 3010);
PAINT MONO (-8640 3010);
DISPLAY INVISIBLE (-8640 3010);
FORCEPROP 2 LAST ROOM MEM_EFGH_DECOUPLING_CAPS
J 0
(-8625 3025);
DISPLAY 0.659574 (-8625 3025);
PAINT RED (-8625 3025);
DISPLAY INVISIBLE (-8625 3025);
FORCEPROP 1 LAST VOLTAGE 0
J 0
(-8670 3045);
DISPLAY 0.829787 (-8670 3045);
PAINT SKYBLUE (-8670 3045);
DISPLAY INVISIBLE (-8670 3045);
FORCEPROP 2 LAST CDS_LIB mstr_symbols
J 0
(-8650 2950);
DISPLAY 0.808511 (-8650 2950);
DISPLAY INVISIBLE (-8650 2950);
FORCEPROP 1 LAST SIZE 1B
J 0
(-8575 2900);
DISPLAY 0.723404 (-8575 2900);
PAINT GREEN (-8575 2900);
DISPLAY INVISIBLE (-8575 2900);
FORCEPROP 2 LAST BOM_COST MEM
J 0
(-8625 3075);
DISPLAY 0.659574 (-8625 3075);
DISPLAY INVISIBLE (-8625 3075);
FORCEPROP 1 LAST BODY_TYPE PLUMBING
J 0
(-8695 2907);
DISPLAY 0.276596 (-8695 2907);
PAINT GREEN (-8695 2907);
DISPLAY INVISIBLE (-8695 2907);
FORCEPROP 1 LAST HDL_POWER GND
J 0
(-8650 3100);
DISPLAY 0.723404 (-8650 3100);
PAINT GREEN (-8650 3100);
DISPLAY INVISIBLE (-8650 3100);
FORCEPROP 1 LAST PATH I187
J 0
(-8575 2950);
DISPLAY 0.872340 (-8575 2950);
PAINT AQUA (-8575 2950);
DISPLAY INVISIBLE (-8575 2950);
FORCEADD OFFPAGE..6
(-9075 2100);
FORCEPROP 2 LAST $XR4 97 
J 0
(-9354 2136);
DISPLAY 0.638298 (-9354 2136);
PAINT MONO (-9354 2136);
FORCEPROP 2 LAST $XR3 96 
J 0
(-9444 2064);
DISPLAY 0.638298 (-9444 2064);
PAINT MONO (-9444 2064);
FORCEPROP 2 LAST $XR2 95 
J 0
(-9354 2064);
DISPLAY 0.638298 (-9354 2064);
PAINT MONO (-9354 2064);
FORCEPROP 2 LAST $XR1 94 
J 0
(-9444 2100);
DISPLAY 0.638298 (-9444 2100);
PAINT MONO (-9444 2100);
FORCEPROP 2 LAST $XR0 92 
J 0
(-9354 2100);
DISPLAY 0.638298 (-9354 2100);
PAINT MONO (-9354 2100);
FORCEPROP 2 LAST CDS_LIB mstr_standard
J 0
(-9075 2100);
DISPLAY INVISIBLE (-9075 2100);
FORCEPROP 1 LAST OFFPAGE TRUE
J 0
(-8750 1975);
DISPLAY 0.872340 (-8750 1975);
PAINT GREEN (-8750 1975);
DISPLAY INVISIBLE (-8750 1975);
FORCEPROP 1 LAST COMMENT_BODY TRUE
J 0
(-8975 2025);
DISPLAY 0.872340 (-8975 2025);
PAINT GREEN (-8975 2025);
DISPLAY INVISIBLE (-8975 2025);
FORCEPROP 2 LAST PATH I188
J 0
(-9025 2175);
DISPLAY 1.021277 (-9025 2175);
DISPLAY INVISIBLE (-9025 2175);
FORCEADD Q_RES..1
R 2
(-8525 2100);
FORCEPROP 1 LAST LOCATION R298
J 2
(-8475 2150);
DISPLAY 0.489362 (-8475 2150);
PAINT SKYBLUE (-8475 2150);
FORCEPROP 0 LAST $SEC 1
J 0
(-8475 2200);
DISPLAY 0.680851 (-8475 2200);
PAINT MONO (-8475 2200);
DISPLAY INVISIBLE (-8475 2200);
FORCEPROP 0 LAST CDS_SEC 1
J 0
(-8475 2200);
DISPLAY 1.021277 (-8475 2200);
DISPLAY INVISIBLE (-8475 2200);
FORCEPROP 1 LASTPIN (-8425 2100) $PN 1
J 2
(-8437 2112);
DISPLAY 0.489362 (-8437 2112);
PAINT MONO (-8437 2112);
FORCEPROP 1 LASTPIN (-8625 2100) $PN 2
J 2
(-8587 2112);
DISPLAY 0.489362 (-8587 2112);
PAINT MONO (-8587 2112);
FORCEPROP 1 LAST VALUE 1K
J 0
(-8525 2050);
DISPLAY 0.489362 (-8525 2050);
PAINT SKYBLUE (-8525 2050);
FORCEPROP 1 LAST PACK_TYPE 0402LF
J 0
(-8700 2025);
DISPLAY 0.489362 (-8700 2025);
PAINT SKYBLUE (-8700 2025);
DISPLAY INVISIBLE (-8700 2025);
FORCEPROP 1 LAST MATERIAL CHIP
J 0
(-8700 2075);
DISPLAY 0.489362 (-8700 2075);
PAINT SKYBLUE (-8700 2075);
DISPLAY INVISIBLE (-8700 2075);
FORCEPROP 1 LAST WATTAGE 1/16W
J 0
(-8450 2025);
DISPLAY 0.489362 (-8450 2025);
PAINT SKYBLUE (-8450 2025);
DISPLAY INVISIBLE (-8450 2025);
FORCEPROP 2 LAST CDS_LIB pure_quanta
J 0
(-8525 2100);
DISPLAY INVISIBLE (-8525 2100);
FORCEPROP 2 LAST BOM_COST MEM
J 0
(-8550 2250);
DISPLAY 0.744681 (-8550 2250);
PAINT WHITE (-8550 2250);
DISPLAY INVISIBLE (-8550 2250);
FORCEPROP 1 LAST TOLERANCE 1%
J 2
(-8400 2075);
DISPLAY 0.489362 (-8400 2075);
PAINT SKYBLUE (-8400 2075);
DISPLAY INVISIBLE (-8400 2075);
FORCEPROP 2 LAST ROOM 
J 0
(-8550 2200);
DISPLAY 0.744681 (-8550 2200);
PAINT RED (-8550 2200);
DISPLAY INVISIBLE (-8550 2200);
FORCEPROP 1 LAST PATH I189
J 2
(-8475 2250);
DISPLAY 0.978723 (-8475 2250);
PAINT WHITE (-8475 2250);
DISPLAY INVISIBLE (-8475 2250);
FORCEPROP 1 LAST PART_NUMBER CS21002FB06
J 0
(-8625 2150);
DISPLAY 0.489362 (-8625 2150);
PAINT SKYBLUE (-8625 2150);
DISPLAY INVISIBLE (-8625 2150);
FORCEADD OFFPAGE..1
(-8325 4550);
FORCEPROP 2 LAST $XR0 17 
J 0
(-8546 4550);
DISPLAY 0.638298 (-8546 4550);
PAINT MONO (-8546 4550);
FORCEPROP 2 LAST CDS_LIB mstr_standard
J 0
(-8325 4550);
DISPLAY 0.723404 (-8325 4550);
PAINT MONO (-8325 4550);
DISPLAY INVISIBLE (-8325 4550);
FORCEPROP 1 LAST OFFPAGE TRUE
J 0
(-8000 4425);
DISPLAY 0.872340 (-8000 4425);
PAINT GREEN (-8000 4425);
DISPLAY INVISIBLE (-8000 4425);
FORCEPROP 1 LAST COMMENT_BODY TRUE
J 0
(-8200 4450);
DISPLAY 0.872340 (-8200 4450);
PAINT GREEN (-8200 4450);
DISPLAY INVISIBLE (-8200 4450);
FORCEPROP 2 LAST PATH I19
J 0
(-8275 4625);
DISPLAY 1.021277 (-8275 4625);
DISPLAY INVISIBLE (-8275 4625);
FORCEADD VCC_CORE..1
(-8400 2425);
FORCEPROP 3 LASTPIN (-8400 2375) SIG_NAME P3V3\g
J 0
(-8390 2385);
DISPLAY 0.659574 (-8390 2385);
PAINT MONO (-8390 2385);
DISPLAY INVISIBLE (-8390 2385);
FORCEPROP 1 LAST HDL_POWER P3V3
J 1
(-8400 2475);
DISPLAY 0.489362 (-8400 2475);
PAINT GREEN (-8400 2475);
FORCEPROP 2 LAST ROOM PVCCINFAON_CPU0_CTRL
J 0
(-8400 2525);
DISPLAY 0.808511 (-8400 2525);
PAINT RED (-8400 2525);
DISPLAY INVISIBLE (-8400 2525);
FORCEPROP 0 LAST VOLTAGE 3.3
J 0
(-8675 2575);
DISPLAY 1.021277 (-8675 2575);
PAINT SKYBLUE (-8675 2575);
DISPLAY INVISIBLE (-8675 2575);
FORCEPROP 2 LAST CDS_LIB mstr_symbols
J 0
(-8400 2425);
DISPLAY INVISIBLE (-8400 2425);
FORCEPROP 1 LAST PATH I190
J 0
(-8350 2450);
DISPLAY 0.872340 (-8350 2450);
PAINT AQUA (-8350 2450);
DISPLAY INVISIBLE (-8350 2450);
FORCEADD Q_RES..2
(-8400 2250);
FORCEPROP 1 LAST LOCATION R97
J 0
(-8355 2375);
DISPLAY 0.489362 (-8355 2375);
PAINT SKYBLUE (-8355 2375);
FORCEPROP 0 LAST $SEC 1
J 0
(-8350 2425);
DISPLAY 0.680851 (-8350 2425);
PAINT MONO (-8350 2425);
DISPLAY INVISIBLE (-8350 2425);
FORCEPROP 0 LAST CDS_SEC 1
J 0
(-8350 2425);
DISPLAY 1.021277 (-8350 2425);
DISPLAY INVISIBLE (-8350 2425);
FORCEPROP 1 LASTPIN (-8400 2350) $PN 1
J 0
(-8395 2312);
DISPLAY 0.489362 (-8395 2312);
PAINT MONO (-8395 2312);
FORCEPROP 1 LASTPIN (-8400 2150) $PN 2
J 0
(-8395 2160);
DISPLAY 0.489362 (-8395 2160);
PAINT MONO (-8395 2160);
FORCEPROP 1 LAST VALUE 1K
J 0
(-8355 2325);
DISPLAY 0.489362 (-8355 2325);
PAINT SKYBLUE (-8355 2325);
FORCEPROP 1 LAST WATTAGE 1/16W
J 0
(-8350 2275);
DISPLAY 0.489362 (-8350 2275);
PAINT SKYBLUE (-8350 2275);
FORCEPROP 1 LAST MATERIAL EMPTY
J 0
(-8350 2250);
DISPLAY 0.489362 (-8350 2250);
PAINT RED (-8350 2250);
FORCEPROP 1 LAST PACK_TYPE 0402LF
J 0
(-8350 2200);
DISPLAY 0.489362 (-8350 2200);
PAINT SKYBLUE (-8350 2200);
FORCEPROP 1 LAST TOLERANCE 1%
J 0
(-8350 2300);
DISPLAY 0.489362 (-8350 2300);
PAINT SKYBLUE (-8350 2300);
FORCEPROP 2 LAST CDS_LIB pure_quanta
J 0
(-8400 2250);
DISPLAY INVISIBLE (-8400 2250);
FORCEPROP 2 LAST BOM_COST MEM
J 0
(-8350 2425);
DISPLAY 0.808511 (-8350 2425);
DISPLAY INVISIBLE (-8350 2425);
FORCEPROP 2 LAST ROOM 
J 0
(-8350 2475);
DISPLAY 0.808511 (-8350 2475);
PAINT RED (-8350 2475);
DISPLAY INVISIBLE (-8350 2475);
FORCEPROP 1 LAST PATH I191
J 0
(-8350 2425);
DISPLAY 0.978723 (-8350 2425);
PAINT WHITE (-8350 2425);
DISPLAY INVISIBLE (-8350 2425);
FORCEPROP 1 LAST PART_NUMBER CS21002FB06
J 0
(-8350 2225);
DISPLAY 0.489362 (-8350 2225);
PAINT SKYBLUE (-8350 2225);
DISPLAY INVISIBLE (-8350 2225);
FORCEADD OFFPAGE..2
(-2500 4350);
FORCEPROP 2 LAST $XR0 17 
J 0
(-2311 4350);
DISPLAY 0.638298 (-2311 4350);
PAINT MONO (-2311 4350);
FORCEPROP 2 LAST CDS_LIB mstr_standard
J 0
(-2500 4350);
DISPLAY 0.723404 (-2500 4350);
PAINT MONO (-2500 4350);
DISPLAY INVISIBLE (-2500 4350);
FORCEPROP 1 LAST OFFPAGE TRUE
J 0
(-2175 4225);
DISPLAY 0.723404 (-2175 4225);
PAINT GREEN (-2175 4225);
DISPLAY INVISIBLE (-2175 4225);
FORCEPROP 1 LAST COMMENT_BODY TRUE
J 0
(-2545 4255);
DISPLAY 0.872340 (-2545 4255);
PAINT GREEN (-2545 4255);
DISPLAY INVISIBLE (-2545 4255);
FORCEPROP 2 LAST PATH I193
J 0
(-2300 4400);
DISPLAY 0.680851 (-2300 4400);
DISPLAY INVISIBLE (-2300 4400);
FORCEADD OFFPAGE..2
(-2500 4400);
FORCEPROP 2 LAST $XR0 17 
J 0
(-2311 4400);
DISPLAY 0.638298 (-2311 4400);
PAINT MONO (-2311 4400);
FORCEPROP 2 LAST CDS_LIB mstr_standard
J 0
(-2500 4400);
DISPLAY 0.723404 (-2500 4400);
PAINT MONO (-2500 4400);
DISPLAY INVISIBLE (-2500 4400);
FORCEPROP 1 LAST OFFPAGE TRUE
J 0
(-2175 4275);
DISPLAY 0.723404 (-2175 4275);
PAINT GREEN (-2175 4275);
DISPLAY INVISIBLE (-2175 4275);
FORCEPROP 1 LAST COMMENT_BODY TRUE
J 0
(-2545 4305);
DISPLAY 0.872340 (-2545 4305);
PAINT GREEN (-2545 4305);
DISPLAY INVISIBLE (-2545 4305);
FORCEPROP 2 LAST PATH I194
J 0
(-2300 4450);
DISPLAY 0.680851 (-2300 4450);
DISPLAY INVISIBLE (-2300 4450);
FORCEADD OFFPAGE..2
(-2500 3300);
FORCEPROP 2 LAST $XR0 17 
J 0
(-2311 3300);
DISPLAY 0.638298 (-2311 3300);
PAINT MONO (-2311 3300);
FORCEPROP 2 LAST CDS_LIB mstr_standard
J 0
(-2500 3300);
DISPLAY 0.723404 (-2500 3300);
PAINT MONO (-2500 3300);
DISPLAY INVISIBLE (-2500 3300);
FORCEPROP 1 LAST OFFPAGE TRUE
J 0
(-2175 3175);
DISPLAY 0.723404 (-2175 3175);
PAINT GREEN (-2175 3175);
DISPLAY INVISIBLE (-2175 3175);
FORCEPROP 1 LAST COMMENT_BODY TRUE
J 0
(-2545 3205);
DISPLAY 0.872340 (-2545 3205);
PAINT GREEN (-2545 3205);
DISPLAY INVISIBLE (-2545 3205);
FORCEPROP 2 LAST PATH I195
J 0
(-2300 3350);
DISPLAY 0.680851 (-2300 3350);
DISPLAY INVISIBLE (-2300 3350);
FORCEADD OFFPAGE..2
(-2500 3350);
FORCEPROP 2 LAST $XR0 17 
J 0
(-2311 3350);
DISPLAY 0.638298 (-2311 3350);
PAINT MONO (-2311 3350);
FORCEPROP 2 LAST CDS_LIB mstr_standard
J 0
(-2500 3350);
DISPLAY 0.723404 (-2500 3350);
PAINT MONO (-2500 3350);
DISPLAY INVISIBLE (-2500 3350);
FORCEPROP 1 LAST OFFPAGE TRUE
J 0
(-2175 3225);
DISPLAY 0.723404 (-2175 3225);
PAINT GREEN (-2175 3225);
DISPLAY INVISIBLE (-2175 3225);
FORCEPROP 1 LAST COMMENT_BODY TRUE
J 0
(-2545 3255);
DISPLAY 0.872340 (-2545 3255);
PAINT GREEN (-2545 3255);
DISPLAY INVISIBLE (-2545 3255);
FORCEPROP 2 LAST PATH I196
J 0
(-2300 3400);
DISPLAY 0.680851 (-2300 3400);
DISPLAY INVISIBLE (-2300 3400);
FORCEADD TAP..1
(-3300 4300);
FORCEPROP 3 LASTPIN (-3350 4300) SIG_NAME M_H_CPU0_SA_DQS_DN<9>
J 0
(-3340 4310);
DISPLAY 0.659574 (-3340 4310);
PAINT MONO (-3340 4310);
DISPLAY INVISIBLE (-3340 4310);
FORCEPROP 1 LASTPIN (-3350 4300) BN 9
J 0
(-3362 4308);
DISPLAY 0.489362 (-3362 4308);
PAINT GREEN (-3362 4308);
FORCEPROP 2 LAST CDS_LIB mstr_standard
J 0
(-3300 4300);
DISPLAY 0.723404 (-3300 4300);
PAINT MONO (-3300 4300);
DISPLAY INVISIBLE (-3300 4300);
FORCEPROP 1 LAST BODY_TYPE PLUMBING
J 0
(-3300 4350);
DISPLAY 0.872340 (-3300 4350);
PAINT GREEN (-3300 4350);
DISPLAY INVISIBLE (-3300 4350);
FORCEPROP 1 LAST HDL_TAP TRUE
J 0
(-2975 4175);
DISPLAY 0.872340 (-2975 4175);
DISPLAY INVISIBLE (-2975 4175);
FORCEPROP 1 LAST PATH I197
J 0
(-3302 4300);
DISPLAY 0.872340 (-3302 4300);
PAINT GREEN (-3302 4300);
DISPLAY INVISIBLE (-3302 4300);
FORCEADD TAP..1
(-3300 4200);
FORCEPROP 3 LASTPIN (-3350 4200) SIG_NAME M_H_CPU0_SA_DQS_DN<8>
J 0
(-3340 4210);
DISPLAY 0.659574 (-3340 4210);
PAINT MONO (-3340 4210);
DISPLAY INVISIBLE (-3340 4210);
FORCEPROP 1 LASTPIN (-3350 4200) BN 8
J 0
(-3362 4208);
DISPLAY 0.489362 (-3362 4208);
PAINT GREEN (-3362 4208);
FORCEPROP 2 LAST CDS_LIB mstr_standard
J 0
(-3300 4200);
DISPLAY 0.723404 (-3300 4200);
PAINT MONO (-3300 4200);
DISPLAY INVISIBLE (-3300 4200);
FORCEPROP 1 LAST BODY_TYPE PLUMBING
J 0
(-3300 4250);
DISPLAY 0.872340 (-3300 4250);
PAINT GREEN (-3300 4250);
DISPLAY INVISIBLE (-3300 4250);
FORCEPROP 1 LAST HDL_TAP TRUE
J 0
(-2975 4075);
DISPLAY 0.872340 (-2975 4075);
DISPLAY INVISIBLE (-2975 4075);
FORCEPROP 1 LAST PATH I198
J 0
(-3302 4200);
DISPLAY 0.872340 (-3302 4200);
PAINT GREEN (-3302 4200);
DISPLAY INVISIBLE (-3302 4200);
FORCEADD TAP..1
(-3500 4350);
FORCEPROP 3 LASTPIN (-3550 4350) SIG_NAME M_H_CPU0_SA_DQS_DP<9>
J 0
(-3540 4360);
DISPLAY 0.659574 (-3540 4360);
PAINT MONO (-3540 4360);
DISPLAY INVISIBLE (-3540 4360);
FORCEPROP 1 LASTPIN (-3550 4350) BN 9
J 0
(-3562 4358);
DISPLAY 0.489362 (-3562 4358);
PAINT GREEN (-3562 4358);
FORCEPROP 2 LAST CDS_LIB mstr_standard
J 0
(-3500 4350);
DISPLAY 0.723404 (-3500 4350);
PAINT MONO (-3500 4350);
DISPLAY INVISIBLE (-3500 4350);
FORCEPROP 1 LAST BODY_TYPE PLUMBING
J 0
(-3500 4400);
DISPLAY 0.872340 (-3500 4400);
PAINT GREEN (-3500 4400);
DISPLAY INVISIBLE (-3500 4400);
FORCEPROP 1 LAST HDL_TAP TRUE
J 0
(-3175 4225);
DISPLAY 0.872340 (-3175 4225);
DISPLAY INVISIBLE (-3175 4225);
FORCEPROP 1 LAST PATH I199
J 0
(-3502 4350);
DISPLAY 0.872340 (-3502 4350);
PAINT GREEN (-3502 4350);
DISPLAY INVISIBLE (-3502 4350);
FORCEADD OFFPAGE..5
(-8325 1900);
FORCEPROP 2 LAST $XR0 17 
J 0
(-8549 1900);
DISPLAY 0.638298 (-8549 1900);
PAINT MONO (-8549 1900);
FORCEPROP 2 LAST CDS_LIB mstr_standard
J 0
(-8325 1900);
DISPLAY 0.808511 (-8325 1900);
DISPLAY INVISIBLE (-8325 1900);
FORCEPROP 1 LAST OFFPAGE TRUE
J 0
(-8000 1775);
DISPLAY 0.872340 (-8000 1775);
PAINT GREEN (-8000 1775);
DISPLAY INVISIBLE (-8000 1775);
FORCEPROP 1 LAST COMMENT_BODY TRUE
J 0
(-8225 1825);
DISPLAY 0.872340 (-8225 1825);
PAINT GREEN (-8225 1825);
DISPLAY INVISIBLE (-8225 1825);
FORCEPROP 2 LAST PATH I2
J 0
(-8275 1975);
DISPLAY 1.021277 (-8275 1975);
DISPLAY INVISIBLE (-8275 1975);
FORCEADD OFFPAGE..1
(-8325 5400);
FORCEPROP 2 LAST $XR0 17 
J 0
(-8546 5400);
DISPLAY 0.638298 (-8546 5400);
PAINT MONO (-8546 5400);
FORCEPROP 2 LAST CDS_LIB mstr_standard
J 0
(-8325 5400);
DISPLAY 0.723404 (-8325 5400);
PAINT MONO (-8325 5400);
DISPLAY INVISIBLE (-8325 5400);
FORCEPROP 1 LAST OFFPAGE TRUE
J 0
(-8000 5275);
DISPLAY 0.872340 (-8000 5275);
PAINT GREEN (-8000 5275);
DISPLAY INVISIBLE (-8000 5275);
FORCEPROP 1 LAST COMMENT_BODY TRUE
J 0
(-8200 5300);
DISPLAY 0.872340 (-8200 5300);
PAINT GREEN (-8200 5300);
DISPLAY INVISIBLE (-8200 5300);
FORCEPROP 2 LAST PATH I20
J 0
(-8275 5475);
DISPLAY 1.021277 (-8275 5475);
DISPLAY INVISIBLE (-8275 5475);
FORCEADD TAP..1
(-3500 4250);
FORCEPROP 3 LASTPIN (-3550 4250) SIG_NAME M_H_CPU0_SA_DQS_DP<8>
J 0
(-3540 4260);
DISPLAY 0.659574 (-3540 4260);
PAINT MONO (-3540 4260);
DISPLAY INVISIBLE (-3540 4260);
FORCEPROP 1 LASTPIN (-3550 4250) BN 8
J 0
(-3562 4258);
DISPLAY 0.489362 (-3562 4258);
PAINT GREEN (-3562 4258);
FORCEPROP 2 LAST CDS_LIB mstr_standard
J 0
(-3500 4250);
DISPLAY 0.723404 (-3500 4250);
PAINT MONO (-3500 4250);
DISPLAY INVISIBLE (-3500 4250);
FORCEPROP 1 LAST BODY_TYPE PLUMBING
J 0
(-3500 4300);
DISPLAY 0.872340 (-3500 4300);
PAINT GREEN (-3500 4300);
DISPLAY INVISIBLE (-3500 4300);
FORCEPROP 1 LAST HDL_TAP TRUE
J 0
(-3175 4125);
DISPLAY 0.872340 (-3175 4125);
DISPLAY INVISIBLE (-3175 4125);
FORCEPROP 1 LAST PATH I200
J 0
(-3502 4250);
DISPLAY 0.872340 (-3502 4250);
PAINT GREEN (-3502 4250);
DISPLAY INVISIBLE (-3502 4250);
FORCEADD TAP..1
(-3300 4100);
FORCEPROP 3 LASTPIN (-3350 4100) SIG_NAME M_H_CPU0_SA_DQS_DN<7>
J 0
(-3340 4110);
DISPLAY 0.659574 (-3340 4110);
PAINT MONO (-3340 4110);
DISPLAY INVISIBLE (-3340 4110);
FORCEPROP 1 LASTPIN (-3350 4100) BN 7
J 0
(-3362 4108);
DISPLAY 0.489362 (-3362 4108);
PAINT GREEN (-3362 4108);
FORCEPROP 2 LAST CDS_LIB mstr_standard
J 0
(-3300 4100);
DISPLAY 0.723404 (-3300 4100);
PAINT MONO (-3300 4100);
DISPLAY INVISIBLE (-3300 4100);
FORCEPROP 1 LAST BODY_TYPE PLUMBING
J 0
(-3300 4150);
DISPLAY 0.872340 (-3300 4150);
PAINT GREEN (-3300 4150);
DISPLAY INVISIBLE (-3300 4150);
FORCEPROP 1 LAST HDL_TAP TRUE
J 0
(-2975 3975);
DISPLAY 0.872340 (-2975 3975);
DISPLAY INVISIBLE (-2975 3975);
FORCEPROP 1 LAST PATH I201
J 0
(-3302 4100);
DISPLAY 0.872340 (-3302 4100);
PAINT GREEN (-3302 4100);
DISPLAY INVISIBLE (-3302 4100);
FORCEADD TAP..1
(-3300 4000);
FORCEPROP 3 LASTPIN (-3350 4000) SIG_NAME M_H_CPU0_SA_DQS_DN<6>
J 0
(-3340 4010);
DISPLAY 0.659574 (-3340 4010);
PAINT MONO (-3340 4010);
DISPLAY INVISIBLE (-3340 4010);
FORCEPROP 1 LASTPIN (-3350 4000) BN 6
J 0
(-3362 4008);
DISPLAY 0.489362 (-3362 4008);
PAINT GREEN (-3362 4008);
FORCEPROP 2 LAST CDS_LIB mstr_standard
J 0
(-3300 4000);
DISPLAY 0.723404 (-3300 4000);
PAINT MONO (-3300 4000);
DISPLAY INVISIBLE (-3300 4000);
FORCEPROP 1 LAST BODY_TYPE PLUMBING
J 0
(-3300 4050);
DISPLAY 0.872340 (-3300 4050);
PAINT GREEN (-3300 4050);
DISPLAY INVISIBLE (-3300 4050);
FORCEPROP 1 LAST HDL_TAP TRUE
J 0
(-2975 3875);
DISPLAY 0.872340 (-2975 3875);
DISPLAY INVISIBLE (-2975 3875);
FORCEPROP 1 LAST PATH I202
J 0
(-3302 4000);
DISPLAY 0.872340 (-3302 4000);
PAINT GREEN (-3302 4000);
DISPLAY INVISIBLE (-3302 4000);
FORCEADD TAP..1
(-3300 3800);
FORCEPROP 3 LASTPIN (-3350 3800) SIG_NAME M_H_CPU0_SA_DQS_DN<4>
J 0
(-3340 3810);
DISPLAY 0.659574 (-3340 3810);
PAINT MONO (-3340 3810);
DISPLAY INVISIBLE (-3340 3810);
FORCEPROP 1 LASTPIN (-3350 3800) BN 4
J 0
(-3362 3808);
DISPLAY 0.489362 (-3362 3808);
PAINT GREEN (-3362 3808);
FORCEPROP 2 LAST CDS_LIB mstr_standard
J 0
(-3300 3800);
DISPLAY 0.723404 (-3300 3800);
PAINT MONO (-3300 3800);
DISPLAY INVISIBLE (-3300 3800);
FORCEPROP 1 LAST BODY_TYPE PLUMBING
J 0
(-3300 3850);
DISPLAY 0.872340 (-3300 3850);
PAINT GREEN (-3300 3850);
DISPLAY INVISIBLE (-3300 3850);
FORCEPROP 1 LAST HDL_TAP TRUE
J 0
(-2975 3675);
DISPLAY 0.872340 (-2975 3675);
DISPLAY INVISIBLE (-2975 3675);
FORCEPROP 1 LAST PATH I203
J 0
(-3302 3800);
DISPLAY 0.872340 (-3302 3800);
PAINT GREEN (-3302 3800);
DISPLAY INVISIBLE (-3302 3800);
FORCEADD TAP..1
(-3300 3900);
FORCEPROP 3 LASTPIN (-3350 3900) SIG_NAME M_H_CPU0_SA_DQS_DN<5>
J 0
(-3340 3910);
DISPLAY 0.659574 (-3340 3910);
PAINT MONO (-3340 3910);
DISPLAY INVISIBLE (-3340 3910);
FORCEPROP 1 LASTPIN (-3350 3900) BN 5
J 0
(-3362 3908);
DISPLAY 0.489362 (-3362 3908);
PAINT GREEN (-3362 3908);
FORCEPROP 2 LAST CDS_LIB mstr_standard
J 0
(-3300 3900);
DISPLAY 0.723404 (-3300 3900);
PAINT MONO (-3300 3900);
DISPLAY INVISIBLE (-3300 3900);
FORCEPROP 1 LAST BODY_TYPE PLUMBING
J 0
(-3300 3950);
DISPLAY 0.872340 (-3300 3950);
PAINT GREEN (-3300 3950);
DISPLAY INVISIBLE (-3300 3950);
FORCEPROP 1 LAST HDL_TAP TRUE
J 0
(-2975 3775);
DISPLAY 0.872340 (-2975 3775);
DISPLAY INVISIBLE (-2975 3775);
FORCEPROP 1 LAST PATH I204
J 0
(-3302 3900);
DISPLAY 0.872340 (-3302 3900);
PAINT GREEN (-3302 3900);
DISPLAY INVISIBLE (-3302 3900);
FORCEADD TAP..1
(-3300 3700);
FORCEPROP 3 LASTPIN (-3350 3700) SIG_NAME M_H_CPU0_SA_DQS_DN<3>
J 0
(-3340 3710);
DISPLAY 0.659574 (-3340 3710);
PAINT MONO (-3340 3710);
DISPLAY INVISIBLE (-3340 3710);
FORCEPROP 1 LASTPIN (-3350 3700) BN 3
J 0
(-3362 3708);
DISPLAY 0.489362 (-3362 3708);
PAINT GREEN (-3362 3708);
FORCEPROP 2 LAST CDS_LIB mstr_standard
J 0
(-3300 3700);
DISPLAY 0.723404 (-3300 3700);
PAINT MONO (-3300 3700);
DISPLAY INVISIBLE (-3300 3700);
FORCEPROP 1 LAST BODY_TYPE PLUMBING
J 0
(-3300 3750);
DISPLAY 0.872340 (-3300 3750);
PAINT GREEN (-3300 3750);
DISPLAY INVISIBLE (-3300 3750);
FORCEPROP 1 LAST HDL_TAP TRUE
J 0
(-2975 3575);
DISPLAY 0.872340 (-2975 3575);
DISPLAY INVISIBLE (-2975 3575);
FORCEPROP 1 LAST PATH I205
J 0
(-3302 3700);
DISPLAY 0.872340 (-3302 3700);
PAINT GREEN (-3302 3700);
DISPLAY INVISIBLE (-3302 3700);
FORCEADD TAP..1
(-3500 3950);
FORCEPROP 3 LASTPIN (-3550 3950) SIG_NAME M_H_CPU0_SA_DQS_DP<5>
J 0
(-3540 3960);
DISPLAY 0.659574 (-3540 3960);
PAINT MONO (-3540 3960);
DISPLAY INVISIBLE (-3540 3960);
FORCEPROP 1 LASTPIN (-3550 3950) BN 5
J 0
(-3562 3958);
DISPLAY 0.489362 (-3562 3958);
PAINT GREEN (-3562 3958);
FORCEPROP 2 LAST CDS_LIB mstr_standard
J 0
(-3500 3950);
DISPLAY 0.723404 (-3500 3950);
PAINT MONO (-3500 3950);
DISPLAY INVISIBLE (-3500 3950);
FORCEPROP 1 LAST BODY_TYPE PLUMBING
J 0
(-3500 4000);
DISPLAY 0.872340 (-3500 4000);
PAINT GREEN (-3500 4000);
DISPLAY INVISIBLE (-3500 4000);
FORCEPROP 1 LAST HDL_TAP TRUE
J 0
(-3175 3825);
DISPLAY 0.872340 (-3175 3825);
DISPLAY INVISIBLE (-3175 3825);
FORCEPROP 1 LAST PATH I206
J 0
(-3502 3950);
DISPLAY 0.872340 (-3502 3950);
PAINT GREEN (-3502 3950);
DISPLAY INVISIBLE (-3502 3950);
FORCEADD TAP..1
(-3500 4150);
FORCEPROP 3 LASTPIN (-3550 4150) SIG_NAME M_H_CPU0_SA_DQS_DP<7>
J 0
(-3540 4160);
DISPLAY 0.659574 (-3540 4160);
PAINT MONO (-3540 4160);
DISPLAY INVISIBLE (-3540 4160);
FORCEPROP 1 LASTPIN (-3550 4150) BN 7
J 0
(-3562 4158);
DISPLAY 0.489362 (-3562 4158);
PAINT GREEN (-3562 4158);
FORCEPROP 2 LAST CDS_LIB mstr_standard
J 0
(-3500 4150);
DISPLAY 0.723404 (-3500 4150);
PAINT MONO (-3500 4150);
DISPLAY INVISIBLE (-3500 4150);
FORCEPROP 1 LAST BODY_TYPE PLUMBING
J 0
(-3500 4200);
DISPLAY 0.872340 (-3500 4200);
PAINT GREEN (-3500 4200);
DISPLAY INVISIBLE (-3500 4200);
FORCEPROP 1 LAST HDL_TAP TRUE
J 0
(-3175 4025);
DISPLAY 0.872340 (-3175 4025);
DISPLAY INVISIBLE (-3175 4025);
FORCEPROP 1 LAST PATH I207
J 0
(-3502 4150);
DISPLAY 0.872340 (-3502 4150);
PAINT GREEN (-3502 4150);
DISPLAY INVISIBLE (-3502 4150);
FORCEADD TAP..1
(-3500 4050);
FORCEPROP 3 LASTPIN (-3550 4050) SIG_NAME M_H_CPU0_SA_DQS_DP<6>
J 0
(-3540 4060);
DISPLAY 0.659574 (-3540 4060);
PAINT MONO (-3540 4060);
DISPLAY INVISIBLE (-3540 4060);
FORCEPROP 1 LASTPIN (-3550 4050) BN 6
J 0
(-3562 4058);
DISPLAY 0.489362 (-3562 4058);
PAINT GREEN (-3562 4058);
FORCEPROP 2 LAST CDS_LIB mstr_standard
J 0
(-3500 4050);
DISPLAY 0.723404 (-3500 4050);
PAINT MONO (-3500 4050);
DISPLAY INVISIBLE (-3500 4050);
FORCEPROP 1 LAST BODY_TYPE PLUMBING
J 0
(-3500 4100);
DISPLAY 0.872340 (-3500 4100);
PAINT GREEN (-3500 4100);
DISPLAY INVISIBLE (-3500 4100);
FORCEPROP 1 LAST HDL_TAP TRUE
J 0
(-3175 3925);
DISPLAY 0.872340 (-3175 3925);
DISPLAY INVISIBLE (-3175 3925);
FORCEPROP 1 LAST PATH I208
J 0
(-3502 4050);
DISPLAY 0.872340 (-3502 4050);
PAINT GREEN (-3502 4050);
DISPLAY INVISIBLE (-3502 4050);
FORCEADD TAP..1
(-3500 3850);
FORCEPROP 3 LASTPIN (-3550 3850) SIG_NAME M_H_CPU0_SA_DQS_DP<4>
J 0
(-3540 3860);
DISPLAY 0.659574 (-3540 3860);
PAINT MONO (-3540 3860);
DISPLAY INVISIBLE (-3540 3860);
FORCEPROP 1 LASTPIN (-3550 3850) BN 4
J 0
(-3562 3858);
DISPLAY 0.489362 (-3562 3858);
PAINT GREEN (-3562 3858);
FORCEPROP 2 LAST CDS_LIB mstr_standard
J 0
(-3500 3850);
DISPLAY 0.723404 (-3500 3850);
PAINT MONO (-3500 3850);
DISPLAY INVISIBLE (-3500 3850);
FORCEPROP 1 LAST BODY_TYPE PLUMBING
J 0
(-3500 3900);
DISPLAY 0.872340 (-3500 3900);
PAINT GREEN (-3500 3900);
DISPLAY INVISIBLE (-3500 3900);
FORCEPROP 1 LAST HDL_TAP TRUE
J 0
(-3175 3725);
DISPLAY 0.872340 (-3175 3725);
DISPLAY INVISIBLE (-3175 3725);
FORCEPROP 1 LAST PATH I209
J 0
(-3502 3850);
DISPLAY 0.872340 (-3502 3850);
PAINT GREEN (-3502 3850);
DISPLAY INVISIBLE (-3502 3850);
FORCEADD OFFPAGE..1
(-8325 5000);
FORCEPROP 2 LAST $XR0 17 
J 0
(-8546 5000);
DISPLAY 0.638298 (-8546 5000);
PAINT MONO (-8546 5000);
FORCEPROP 2 LAST CDS_LIB mstr_standard
J 0
(-8325 5000);
DISPLAY 0.723404 (-8325 5000);
PAINT MONO (-8325 5000);
DISPLAY INVISIBLE (-8325 5000);
FORCEPROP 1 LAST OFFPAGE TRUE
J 0
(-8000 4875);
DISPLAY 0.872340 (-8000 4875);
PAINT GREEN (-8000 4875);
DISPLAY INVISIBLE (-8000 4875);
FORCEPROP 1 LAST COMMENT_BODY TRUE
J 0
(-8200 4900);
DISPLAY 0.872340 (-8200 4900);
PAINT GREEN (-8200 4900);
DISPLAY INVISIBLE (-8200 4900);
FORCEPROP 2 LAST PATH I21
J 0
(-8275 5075);
DISPLAY 1.021277 (-8275 5075);
DISPLAY INVISIBLE (-8275 5075);
FORCEADD TAP..1
(-3500 3750);
FORCEPROP 3 LASTPIN (-3550 3750) SIG_NAME M_H_CPU0_SA_DQS_DP<3>
J 0
(-3540 3760);
DISPLAY 0.659574 (-3540 3760);
PAINT MONO (-3540 3760);
DISPLAY INVISIBLE (-3540 3760);
FORCEPROP 1 LASTPIN (-3550 3750) BN 3
J 0
(-3562 3758);
DISPLAY 0.489362 (-3562 3758);
PAINT GREEN (-3562 3758);
FORCEPROP 2 LAST CDS_LIB mstr_standard
J 0
(-3500 3750);
DISPLAY 0.723404 (-3500 3750);
PAINT MONO (-3500 3750);
DISPLAY INVISIBLE (-3500 3750);
FORCEPROP 1 LAST BODY_TYPE PLUMBING
J 0
(-3500 3800);
DISPLAY 0.872340 (-3500 3800);
PAINT GREEN (-3500 3800);
DISPLAY INVISIBLE (-3500 3800);
FORCEPROP 1 LAST HDL_TAP TRUE
J 0
(-3175 3625);
DISPLAY 0.872340 (-3175 3625);
DISPLAY INVISIBLE (-3175 3625);
FORCEPROP 1 LAST PATH I210
J 0
(-3502 3750);
DISPLAY 0.872340 (-3502 3750);
PAINT GREEN (-3502 3750);
DISPLAY INVISIBLE (-3502 3750);
FORCEADD TAP..1
(-3300 3600);
FORCEPROP 3 LASTPIN (-3350 3600) SIG_NAME M_H_CPU0_SA_DQS_DN<2>
J 0
(-3340 3610);
DISPLAY 0.659574 (-3340 3610);
PAINT MONO (-3340 3610);
DISPLAY INVISIBLE (-3340 3610);
FORCEPROP 1 LASTPIN (-3350 3600) BN 2
J 0
(-3362 3608);
DISPLAY 0.489362 (-3362 3608);
PAINT GREEN (-3362 3608);
FORCEPROP 2 LAST CDS_LIB mstr_standard
J 0
(-3300 3600);
DISPLAY 0.723404 (-3300 3600);
PAINT MONO (-3300 3600);
DISPLAY INVISIBLE (-3300 3600);
FORCEPROP 1 LAST BODY_TYPE PLUMBING
J 0
(-3300 3650);
DISPLAY 0.872340 (-3300 3650);
PAINT GREEN (-3300 3650);
DISPLAY INVISIBLE (-3300 3650);
FORCEPROP 1 LAST HDL_TAP TRUE
J 0
(-2975 3475);
DISPLAY 0.872340 (-2975 3475);
DISPLAY INVISIBLE (-2975 3475);
FORCEPROP 1 LAST PATH I211
J 0
(-3302 3600);
DISPLAY 0.872340 (-3302 3600);
PAINT GREEN (-3302 3600);
DISPLAY INVISIBLE (-3302 3600);
FORCEADD TAP..1
(-3300 3500);
FORCEPROP 3 LASTPIN (-3350 3500) SIG_NAME M_H_CPU0_SA_DQS_DN<1>
J 0
(-3340 3510);
DISPLAY 0.659574 (-3340 3510);
PAINT MONO (-3340 3510);
DISPLAY INVISIBLE (-3340 3510);
FORCEPROP 1 LASTPIN (-3350 3500) BN 1
J 0
(-3362 3508);
DISPLAY 0.489362 (-3362 3508);
PAINT GREEN (-3362 3508);
FORCEPROP 2 LAST CDS_LIB mstr_standard
J 0
(-3300 3500);
DISPLAY 0.723404 (-3300 3500);
PAINT MONO (-3300 3500);
DISPLAY INVISIBLE (-3300 3500);
FORCEPROP 1 LAST BODY_TYPE PLUMBING
J 0
(-3300 3550);
DISPLAY 0.872340 (-3300 3550);
PAINT GREEN (-3300 3550);
DISPLAY INVISIBLE (-3300 3550);
FORCEPROP 1 LAST HDL_TAP TRUE
J 0
(-2975 3375);
DISPLAY 0.872340 (-2975 3375);
DISPLAY INVISIBLE (-2975 3375);
FORCEPROP 1 LAST PATH I212
J 0
(-3302 3500);
DISPLAY 0.872340 (-3302 3500);
PAINT GREEN (-3302 3500);
DISPLAY INVISIBLE (-3302 3500);
FORCEADD TAP..1
(-3300 3400);
FORCEPROP 3 LASTPIN (-3350 3400) SIG_NAME M_H_CPU0_SA_DQS_DN<0>
J 0
(-3340 3410);
DISPLAY 0.659574 (-3340 3410);
PAINT MONO (-3340 3410);
DISPLAY INVISIBLE (-3340 3410);
FORCEPROP 1 LASTPIN (-3350 3400) BN 0
J 0
(-3362 3408);
DISPLAY 0.489362 (-3362 3408);
PAINT GREEN (-3362 3408);
FORCEPROP 2 LAST CDS_LIB mstr_standard
J 0
(-3300 3400);
DISPLAY 0.723404 (-3300 3400);
PAINT MONO (-3300 3400);
DISPLAY INVISIBLE (-3300 3400);
FORCEPROP 1 LAST BODY_TYPE PLUMBING
J 0
(-3300 3450);
DISPLAY 0.872340 (-3300 3450);
PAINT GREEN (-3300 3450);
DISPLAY INVISIBLE (-3300 3450);
FORCEPROP 1 LAST HDL_TAP TRUE
J 0
(-2975 3275);
DISPLAY 0.872340 (-2975 3275);
DISPLAY INVISIBLE (-2975 3275);
FORCEPROP 1 LAST PATH I213
J 0
(-3302 3400);
DISPLAY 0.872340 (-3302 3400);
PAINT GREEN (-3302 3400);
DISPLAY INVISIBLE (-3302 3400);
FORCEADD TAP..1
(-3300 3150);
FORCEPROP 3 LASTPIN (-3350 3150) SIG_NAME M_H_CPU0_SB_DQS_DN<8>
J 0
(-3340 3160);
DISPLAY 0.659574 (-3340 3160);
PAINT MONO (-3340 3160);
DISPLAY INVISIBLE (-3340 3160);
FORCEPROP 1 LASTPIN (-3350 3150) BN 8
J 0
(-3362 3158);
DISPLAY 0.489362 (-3362 3158);
PAINT GREEN (-3362 3158);
FORCEPROP 2 LAST CDS_LIB mstr_standard
J 0
(-3300 3150);
DISPLAY 0.723404 (-3300 3150);
PAINT MONO (-3300 3150);
DISPLAY INVISIBLE (-3300 3150);
FORCEPROP 1 LAST BODY_TYPE PLUMBING
J 0
(-3300 3200);
DISPLAY 0.872340 (-3300 3200);
PAINT GREEN (-3300 3200);
DISPLAY INVISIBLE (-3300 3200);
FORCEPROP 1 LAST HDL_TAP TRUE
J 0
(-2975 3025);
DISPLAY 0.872340 (-2975 3025);
DISPLAY INVISIBLE (-2975 3025);
FORCEPROP 1 LAST PATH I214
J 0
(-3302 3150);
DISPLAY 0.872340 (-3302 3150);
PAINT GREEN (-3302 3150);
DISPLAY INVISIBLE (-3302 3150);
FORCEADD TAP..1
(-3300 3250);
FORCEPROP 3 LASTPIN (-3350 3250) SIG_NAME M_H_CPU0_SB_DQS_DN<9>
J 0
(-3340 3260);
DISPLAY 0.659574 (-3340 3260);
PAINT MONO (-3340 3260);
DISPLAY INVISIBLE (-3340 3260);
FORCEPROP 1 LASTPIN (-3350 3250) BN 9
J 0
(-3362 3258);
DISPLAY 0.489362 (-3362 3258);
PAINT GREEN (-3362 3258);
FORCEPROP 2 LAST CDS_LIB mstr_standard
J 0
(-3300 3250);
DISPLAY 0.723404 (-3300 3250);
PAINT MONO (-3300 3250);
DISPLAY INVISIBLE (-3300 3250);
FORCEPROP 1 LAST BODY_TYPE PLUMBING
J 0
(-3300 3300);
DISPLAY 0.872340 (-3300 3300);
PAINT GREEN (-3300 3300);
DISPLAY INVISIBLE (-3300 3300);
FORCEPROP 1 LAST HDL_TAP TRUE
J 0
(-2975 3125);
DISPLAY 0.872340 (-2975 3125);
DISPLAY INVISIBLE (-2975 3125);
FORCEPROP 1 LAST PATH I215
J 0
(-3302 3250);
DISPLAY 0.872340 (-3302 3250);
PAINT GREEN (-3302 3250);
DISPLAY INVISIBLE (-3302 3250);
FORCEADD TAP..1
(-3500 3450);
FORCEPROP 3 LASTPIN (-3550 3450) SIG_NAME M_H_CPU0_SA_DQS_DP<0>
J 0
(-3540 3460);
DISPLAY 0.659574 (-3540 3460);
PAINT MONO (-3540 3460);
DISPLAY INVISIBLE (-3540 3460);
FORCEPROP 1 LASTPIN (-3550 3450) BN 0
J 0
(-3562 3458);
DISPLAY 0.489362 (-3562 3458);
PAINT GREEN (-3562 3458);
FORCEPROP 2 LAST CDS_LIB mstr_standard
J 0
(-3500 3450);
DISPLAY 0.723404 (-3500 3450);
PAINT MONO (-3500 3450);
DISPLAY INVISIBLE (-3500 3450);
FORCEPROP 1 LAST BODY_TYPE PLUMBING
J 0
(-3500 3500);
DISPLAY 0.872340 (-3500 3500);
PAINT GREEN (-3500 3500);
DISPLAY INVISIBLE (-3500 3500);
FORCEPROP 1 LAST HDL_TAP TRUE
J 0
(-3175 3325);
DISPLAY 0.872340 (-3175 3325);
DISPLAY INVISIBLE (-3175 3325);
FORCEPROP 1 LAST PATH I216
J 0
(-3502 3450);
DISPLAY 0.872340 (-3502 3450);
PAINT GREEN (-3502 3450);
DISPLAY INVISIBLE (-3502 3450);
FORCEADD TAP..1
(-3500 3650);
FORCEPROP 3 LASTPIN (-3550 3650) SIG_NAME M_H_CPU0_SA_DQS_DP<2>
J 0
(-3540 3660);
DISPLAY 0.659574 (-3540 3660);
PAINT MONO (-3540 3660);
DISPLAY INVISIBLE (-3540 3660);
FORCEPROP 1 LASTPIN (-3550 3650) BN 2
J 0
(-3562 3658);
DISPLAY 0.489362 (-3562 3658);
PAINT GREEN (-3562 3658);
FORCEPROP 2 LAST CDS_LIB mstr_standard
J 0
(-3500 3650);
DISPLAY 0.723404 (-3500 3650);
PAINT MONO (-3500 3650);
DISPLAY INVISIBLE (-3500 3650);
FORCEPROP 1 LAST BODY_TYPE PLUMBING
J 0
(-3500 3700);
DISPLAY 0.872340 (-3500 3700);
PAINT GREEN (-3500 3700);
DISPLAY INVISIBLE (-3500 3700);
FORCEPROP 1 LAST HDL_TAP TRUE
J 0
(-3175 3525);
DISPLAY 0.872340 (-3175 3525);
DISPLAY INVISIBLE (-3175 3525);
FORCEPROP 1 LAST PATH I217
J 0
(-3502 3650);
DISPLAY 0.872340 (-3502 3650);
PAINT GREEN (-3502 3650);
DISPLAY INVISIBLE (-3502 3650);
FORCEADD TAP..1
(-3500 3550);
FORCEPROP 3 LASTPIN (-3550 3550) SIG_NAME M_H_CPU0_SA_DQS_DP<1>
J 0
(-3540 3560);
DISPLAY 0.659574 (-3540 3560);
PAINT MONO (-3540 3560);
DISPLAY INVISIBLE (-3540 3560);
FORCEPROP 1 LASTPIN (-3550 3550) BN 1
J 0
(-3562 3558);
DISPLAY 0.489362 (-3562 3558);
PAINT GREEN (-3562 3558);
FORCEPROP 2 LAST CDS_LIB mstr_standard
J 0
(-3500 3550);
DISPLAY 0.723404 (-3500 3550);
PAINT MONO (-3500 3550);
DISPLAY INVISIBLE (-3500 3550);
FORCEPROP 1 LAST BODY_TYPE PLUMBING
J 0
(-3500 3600);
DISPLAY 0.872340 (-3500 3600);
PAINT GREEN (-3500 3600);
DISPLAY INVISIBLE (-3500 3600);
FORCEPROP 1 LAST HDL_TAP TRUE
J 0
(-3175 3425);
DISPLAY 0.872340 (-3175 3425);
DISPLAY INVISIBLE (-3175 3425);
FORCEPROP 1 LAST PATH I218
J 0
(-3502 3550);
DISPLAY 0.872340 (-3502 3550);
PAINT GREEN (-3502 3550);
DISPLAY INVISIBLE (-3502 3550);
FORCEADD TAP..1
(-3500 3200);
FORCEPROP 3 LASTPIN (-3550 3200) SIG_NAME M_H_CPU0_SB_DQS_DP<8>
J 0
(-3540 3210);
DISPLAY 0.659574 (-3540 3210);
PAINT MONO (-3540 3210);
DISPLAY INVISIBLE (-3540 3210);
FORCEPROP 1 LASTPIN (-3550 3200) BN 8
J 0
(-3562 3208);
DISPLAY 0.489362 (-3562 3208);
PAINT GREEN (-3562 3208);
FORCEPROP 2 LAST CDS_LIB mstr_standard
J 0
(-3500 3200);
DISPLAY 0.723404 (-3500 3200);
PAINT MONO (-3500 3200);
DISPLAY INVISIBLE (-3500 3200);
FORCEPROP 1 LAST BODY_TYPE PLUMBING
J 0
(-3500 3250);
DISPLAY 0.872340 (-3500 3250);
PAINT GREEN (-3500 3250);
DISPLAY INVISIBLE (-3500 3250);
FORCEPROP 1 LAST HDL_TAP TRUE
J 0
(-3175 3075);
DISPLAY 0.872340 (-3175 3075);
DISPLAY INVISIBLE (-3175 3075);
FORCEPROP 1 LAST PATH I219
J 0
(-3502 3200);
DISPLAY 0.872340 (-3502 3200);
PAINT GREEN (-3502 3200);
DISPLAY INVISIBLE (-3502 3200);
FORCEADD SCONN288_DDR506112002KQ..1
(-6875 3600);
FORCEPROP 1 LAST LOCATION J69
J 0
(-7325 5675);
DISPLAY 0.468085 (-7325 5675);
PAINT SKYBLUE (-7325 5675);
FORCEPROP 0 LAST $SEC 1
J 0
(-7325 5825);
DISPLAY 0.680851 (-7325 5825);
PAINT MONO (-7325 5825);
DISPLAY INVISIBLE (-7325 5825);
FORCEPROP 2 LAST CDS_SEC 1
J 0
(-7325 5825);
DISPLAY 1.021277 (-7325 5825);
DISPLAY INVISIBLE (-7325 5825);
FORCEPROP 0 LASTPIN (-7475 3000) $PN 62
J 2
(-7485 3010);
DISPLAY 0.680851 (-7485 3010);
PAINT MONO (-7485 3010);
FORCEPROP 0 LASTPIN (-7475 5050) $PN 66
J 2
(-7485 5060);
DISPLAY 0.680851 (-7485 5060);
PAINT MONO (-7485 5060);
FORCEPROP 0 LASTPIN (-7475 4650) $PN 76
J 2
(-7485 4660);
DISPLAY 0.680851 (-7485 4660);
PAINT MONO (-7485 4660);
FORCEPROP 0 LASTPIN (-7475 5100) $PN 211
J 2
(-7485 5110);
DISPLAY 0.680851 (-7485 5110);
PAINT MONO (-7485 5110);
FORCEPROP 0 LASTPIN (-7475 4700) $PN 221
J 2
(-7485 4710);
DISPLAY 0.680851 (-7485 4710);
PAINT MONO (-7485 4710);
FORCEPROP 0 LASTPIN (-7475 5150) $PN 68
J 2
(-7485 5160);
DISPLAY 0.680851 (-7485 5160);
PAINT MONO (-7485 5160);
FORCEPROP 0 LASTPIN (-7475 4750) $PN 78
J 2
(-7485 4760);
DISPLAY 0.680851 (-7485 4760);
PAINT MONO (-7485 4760);
FORCEPROP 0 LASTPIN (-7475 5200) $PN 213
J 2
(-7485 5210);
DISPLAY 0.680851 (-7485 5210);
PAINT MONO (-7485 5210);
FORCEPROP 0 LASTPIN (-7475 4800) $PN 223
J 2
(-7485 4810);
DISPLAY 0.680851 (-7485 4810);
PAINT MONO (-7485 4810);
FORCEPROP 0 LASTPIN (-7475 5250) $PN 70
J 2
(-7485 5260);
DISPLAY 0.680851 (-7485 5260);
PAINT MONO (-7485 5260);
FORCEPROP 0 LASTPIN (-7475 4850) $PN 80
J 2
(-7485 4860);
DISPLAY 0.680851 (-7485 4860);
PAINT MONO (-7485 4860);
FORCEPROP 0 LASTPIN (-7475 5300) $PN 215
J 2
(-7485 5310);
DISPLAY 0.680851 (-7485 5310);
PAINT MONO (-7485 5310);
FORCEPROP 0 LASTPIN (-7475 4900) $PN 225
J 2
(-7485 4910);
DISPLAY 0.680851 (-7485 4910);
PAINT MONO (-7485 4910);
FORCEPROP 0 LASTPIN (-7475 5350) $PN 72
J 2
(-7485 5360);
DISPLAY 0.680851 (-7485 5360);
PAINT MONO (-7485 5360);
FORCEPROP 0 LASTPIN (-7475 4950) $PN 82
J 2
(-7485 4960);
DISPLAY 0.680851 (-7485 4960);
PAINT MONO (-7485 4960);
FORCEPROP 0 LASTPIN (-7475 3600) $PN 51
J 2
(-7485 3610);
DISPLAY 0.680851 (-7485 3610);
PAINT MONO (-7485 3610);
FORCEPROP 0 LASTPIN (-7475 3150) $PN 96
J 2
(-7485 3160);
DISPLAY 0.680851 (-7485 3160);
PAINT MONO (-7485 3160);
FORCEPROP 0 LASTPIN (-7475 3650) $PN 53
J 2
(-7485 3660);
DISPLAY 0.680851 (-7485 3660);
PAINT MONO (-7485 3660);
FORCEPROP 0 LASTPIN (-7475 3200) $PN 98
J 2
(-7485 3210);
DISPLAY 0.680851 (-7485 3210);
PAINT MONO (-7485 3210);
FORCEPROP 0 LASTPIN (-7475 3700) $PN 196
J 2
(-7485 3710);
DISPLAY 0.680851 (-7485 3710);
PAINT MONO (-7485 3710);
FORCEPROP 0 LASTPIN (-7475 3250) $PN 241
J 2
(-7485 3260);
DISPLAY 0.680851 (-7485 3260);
PAINT MONO (-7485 3260);
FORCEPROP 0 LASTPIN (-7475 3750) $PN 198
J 2
(-7485 3760);
DISPLAY 0.680851 (-7485 3760);
PAINT MONO (-7485 3760);
FORCEPROP 0 LASTPIN (-7475 3300) $PN 243
J 2
(-7485 3310);
DISPLAY 0.680851 (-7485 3310);
PAINT MONO (-7485 3310);
FORCEPROP 0 LASTPIN (-7475 3800) $PN 58
J 2
(-7485 3810);
DISPLAY 0.680851 (-7485 3810);
PAINT MONO (-7485 3810);
FORCEPROP 0 LASTPIN (-7475 3350) $PN 89
J 2
(-7485 3360);
DISPLAY 0.680851 (-7485 3360);
PAINT MONO (-7485 3360);
FORCEPROP 0 LASTPIN (-7475 3850) $PN 60
J 2
(-7485 3860);
DISPLAY 0.680851 (-7485 3860);
PAINT MONO (-7485 3860);
FORCEPROP 0 LASTPIN (-7475 3400) $PN 91
J 2
(-7485 3410);
DISPLAY 0.680851 (-7485 3410);
PAINT MONO (-7485 3410);
FORCEPROP 0 LASTPIN (-7475 3900) $PN 203
J 2
(-7485 3910);
DISPLAY 0.680851 (-7485 3910);
PAINT MONO (-7485 3910);
FORCEPROP 0 LASTPIN (-7475 3450) $PN 234
J 2
(-7485 3460);
DISPLAY 0.680851 (-7485 3460);
PAINT MONO (-7485 3460);
FORCEPROP 0 LASTPIN (-7475 3950) $PN 205
J 2
(-7485 3960);
DISPLAY 0.680851 (-7485 3960);
PAINT MONO (-7485 3960);
FORCEPROP 0 LASTPIN (-7475 3500) $PN 236
J 2
(-7485 3510);
DISPLAY 0.680851 (-7485 3510);
PAINT MONO (-7485 3510);
FORCEPROP 0 LASTPIN (-7475 4050) $PN 218
J 2
(-7485 4060);
DISPLAY 0.680851 (-7485 4060);
PAINT MONO (-7485 4060);
FORCEPROP 0 LASTPIN (-7475 4100) $PN 217
J 2
(-7485 4110);
DISPLAY 0.680851 (-7485 4110);
PAINT MONO (-7485 4110);
FORCEPROP 0 LASTPIN (-7475 4350) $PN 64
J 2
(-7485 4360);
DISPLAY 0.680851 (-7485 4360);
PAINT MONO (-7485 4360);
FORCEPROP 0 LASTPIN (-7475 4200) $PN 84
J 2
(-7485 4210);
DISPLAY 0.680851 (-7485 4210);
PAINT MONO (-7485 4210);
FORCEPROP 0 LASTPIN (-7475 4400) $PN 209
J 2
(-7485 4410);
DISPLAY 0.680851 (-7485 4410);
PAINT MONO (-7485 4410);
FORCEPROP 0 LASTPIN (-7475 4250) $PN 229
J 2
(-7485 4260);
DISPLAY 0.680851 (-7485 4260);
PAINT MONO (-7485 4260);
FORCEPROP 0 LASTPIN (-6275 3800) $PN 7
J 0
(-6265 3810);
DISPLAY 0.680851 (-6265 3810);
PAINT MONO (-6265 3810);
FORCEPROP 0 LASTPIN (-6275 2150) $PN 100
J 0
(-6265 2160);
DISPLAY 0.680851 (-6265 2160);
PAINT MONO (-6265 2160);
FORCEPROP 0 LASTPIN (-6275 3850) $PN 9
J 0
(-6265 3860);
DISPLAY 0.680851 (-6265 3860);
PAINT MONO (-6265 3860);
FORCEPROP 0 LASTPIN (-6275 2200) $PN 102
J 0
(-6265 2210);
DISPLAY 0.680851 (-6265 2210);
PAINT MONO (-6265 2210);
FORCEPROP 0 LASTPIN (-6275 3900) $PN 152
J 0
(-6265 3910);
DISPLAY 0.680851 (-6265 3910);
PAINT MONO (-6265 3910);
FORCEPROP 0 LASTPIN (-6275 2250) $PN 245
J 0
(-6265 2260);
DISPLAY 0.680851 (-6265 2260);
PAINT MONO (-6265 2260);
FORCEPROP 0 LASTPIN (-6275 3950) $PN 154
J 0
(-6265 3960);
DISPLAY 0.680851 (-6265 3960);
PAINT MONO (-6265 3960);
FORCEPROP 0 LASTPIN (-6275 2300) $PN 247
J 0
(-6265 2310);
DISPLAY 0.680851 (-6265 2310);
PAINT MONO (-6265 2310);
FORCEPROP 0 LASTPIN (-6275 4000) $PN 14
J 0
(-6265 4010);
DISPLAY 0.680851 (-6265 4010);
PAINT MONO (-6265 4010);
FORCEPROP 0 LASTPIN (-6275 2350) $PN 107
J 0
(-6265 2360);
DISPLAY 0.680851 (-6265 2360);
PAINT MONO (-6265 2360);
FORCEPROP 0 LASTPIN (-6275 4050) $PN 16
J 0
(-6265 4060);
DISPLAY 0.680851 (-6265 4060);
PAINT MONO (-6265 4060);
FORCEPROP 0 LASTPIN (-6275 2400) $PN 109
J 0
(-6265 2410);
DISPLAY 0.680851 (-6265 2410);
PAINT MONO (-6265 2410);
FORCEPROP 0 LASTPIN (-6275 4100) $PN 159
J 0
(-6265 4110);
DISPLAY 0.680851 (-6265 4110);
PAINT MONO (-6265 4110);
FORCEPROP 0 LASTPIN (-6275 2450) $PN 252
J 0
(-6265 2460);
DISPLAY 0.680851 (-6265 2460);
PAINT MONO (-6265 2460);
FORCEPROP 0 LASTPIN (-6275 4150) $PN 161
J 0
(-6265 4160);
DISPLAY 0.680851 (-6265 4160);
PAINT MONO (-6265 4160);
FORCEPROP 0 LASTPIN (-6275 2500) $PN 254
J 0
(-6265 2510);
DISPLAY 0.680851 (-6265 2510);
PAINT MONO (-6265 2510);
FORCEPROP 0 LASTPIN (-6275 4200) $PN 18
J 0
(-6265 4210);
DISPLAY 0.680851 (-6265 4210);
PAINT MONO (-6265 4210);
FORCEPROP 0 LASTPIN (-6275 2550) $PN 111
J 0
(-6265 2560);
DISPLAY 0.680851 (-6265 2560);
PAINT MONO (-6265 2560);
FORCEPROP 0 LASTPIN (-6275 4250) $PN 20
J 0
(-6265 4260);
DISPLAY 0.680851 (-6265 4260);
PAINT MONO (-6265 4260);
FORCEPROP 0 LASTPIN (-6275 2600) $PN 113
J 0
(-6265 2610);
DISPLAY 0.680851 (-6265 2610);
PAINT MONO (-6265 2610);
FORCEPROP 0 LASTPIN (-6275 4300) $PN 163
J 0
(-6265 4310);
DISPLAY 0.680851 (-6265 4310);
PAINT MONO (-6265 4310);
FORCEPROP 0 LASTPIN (-6275 2650) $PN 256
J 0
(-6265 2660);
DISPLAY 0.680851 (-6265 2660);
PAINT MONO (-6265 2660);
FORCEPROP 0 LASTPIN (-6275 4350) $PN 165
J 0
(-6265 4360);
DISPLAY 0.680851 (-6265 4360);
PAINT MONO (-6265 4360);
FORCEPROP 0 LASTPIN (-6275 2700) $PN 258
J 0
(-6265 2710);
DISPLAY 0.680851 (-6265 2710);
PAINT MONO (-6265 2710);
FORCEPROP 0 LASTPIN (-6275 4400) $PN 25
J 0
(-6265 4410);
DISPLAY 0.680851 (-6265 4410);
PAINT MONO (-6265 4410);
FORCEPROP 0 LASTPIN (-6275 2750) $PN 118
J 0
(-6265 2760);
DISPLAY 0.680851 (-6265 2760);
PAINT MONO (-6265 2760);
FORCEPROP 0 LASTPIN (-6275 4450) $PN 27
J 0
(-6265 4460);
DISPLAY 0.680851 (-6265 4460);
PAINT MONO (-6265 4460);
FORCEPROP 0 LASTPIN (-6275 2800) $PN 120
J 0
(-6265 2810);
DISPLAY 0.680851 (-6265 2810);
PAINT MONO (-6265 2810);
FORCEPROP 0 LASTPIN (-6275 4500) $PN 170
J 0
(-6265 4510);
DISPLAY 0.680851 (-6265 4510);
PAINT MONO (-6265 4510);
FORCEPROP 0 LASTPIN (-6275 2850) $PN 263
J 0
(-6265 2860);
DISPLAY 0.680851 (-6265 2860);
PAINT MONO (-6265 2860);
FORCEPROP 0 LASTPIN (-6275 4550) $PN 172
J 0
(-6265 4560);
DISPLAY 0.680851 (-6265 4560);
PAINT MONO (-6265 4560);
FORCEPROP 0 LASTPIN (-6275 2900) $PN 265
J 0
(-6265 2910);
DISPLAY 0.680851 (-6265 2910);
PAINT MONO (-6265 2910);
FORCEPROP 0 LASTPIN (-6275 4600) $PN 29
J 0
(-6265 4610);
DISPLAY 0.680851 (-6265 4610);
PAINT MONO (-6265 4610);
FORCEPROP 0 LASTPIN (-6275 2950) $PN 122
J 0
(-6265 2960);
DISPLAY 0.680851 (-6265 2960);
PAINT MONO (-6265 2960);
FORCEPROP 0 LASTPIN (-6275 4650) $PN 31
J 0
(-6265 4660);
DISPLAY 0.680851 (-6265 4660);
PAINT MONO (-6265 4660);
FORCEPROP 0 LASTPIN (-6275 3000) $PN 124
J 0
(-6265 3010);
DISPLAY 0.680851 (-6265 3010);
PAINT MONO (-6265 3010);
FORCEPROP 0 LASTPIN (-6275 4700) $PN 174
J 0
(-6265 4710);
DISPLAY 0.680851 (-6265 4710);
PAINT MONO (-6265 4710);
FORCEPROP 0 LASTPIN (-6275 3050) $PN 267
J 0
(-6265 3060);
DISPLAY 0.680851 (-6265 3060);
PAINT MONO (-6265 3060);
FORCEPROP 0 LASTPIN (-6275 4750) $PN 176
J 0
(-6265 4760);
DISPLAY 0.680851 (-6265 4760);
PAINT MONO (-6265 4760);
FORCEPROP 0 LASTPIN (-6275 3100) $PN 269
J 0
(-6265 3110);
DISPLAY 0.680851 (-6265 3110);
PAINT MONO (-6265 3110);
FORCEPROP 0 LASTPIN (-6275 4800) $PN 36
J 0
(-6265 4810);
DISPLAY 0.680851 (-6265 4810);
PAINT MONO (-6265 4810);
FORCEPROP 0 LASTPIN (-6275 3150) $PN 129
J 0
(-6265 3160);
DISPLAY 0.680851 (-6265 3160);
PAINT MONO (-6265 3160);
FORCEPROP 0 LASTPIN (-6275 4850) $PN 38
J 0
(-6265 4860);
DISPLAY 0.680851 (-6265 4860);
PAINT MONO (-6265 4860);
FORCEPROP 0 LASTPIN (-6275 3200) $PN 131
J 0
(-6265 3210);
DISPLAY 0.680851 (-6265 3210);
PAINT MONO (-6265 3210);
FORCEPROP 0 LASTPIN (-6275 4900) $PN 181
J 0
(-6265 4910);
DISPLAY 0.680851 (-6265 4910);
PAINT MONO (-6265 4910);
FORCEPROP 0 LASTPIN (-6275 3250) $PN 274
J 0
(-6265 3260);
DISPLAY 0.680851 (-6265 3260);
PAINT MONO (-6265 3260);
FORCEPROP 0 LASTPIN (-6275 4950) $PN 183
J 0
(-6265 4960);
DISPLAY 0.680851 (-6265 4960);
PAINT MONO (-6265 4960);
FORCEPROP 0 LASTPIN (-6275 3300) $PN 276
J 0
(-6265 3310);
DISPLAY 0.680851 (-6265 3310);
PAINT MONO (-6265 3310);
FORCEPROP 0 LASTPIN (-6275 5000) $PN 40
J 0
(-6265 5010);
DISPLAY 0.680851 (-6265 5010);
PAINT MONO (-6265 5010);
FORCEPROP 0 LASTPIN (-6275 3350) $PN 133
J 0
(-6265 3360);
DISPLAY 0.680851 (-6265 3360);
PAINT MONO (-6265 3360);
FORCEPROP 0 LASTPIN (-6275 5050) $PN 42
J 0
(-6265 5060);
DISPLAY 0.680851 (-6265 5060);
PAINT MONO (-6265 5060);
FORCEPROP 0 LASTPIN (-6275 3400) $PN 135
J 0
(-6265 3410);
DISPLAY 0.680851 (-6265 3410);
PAINT MONO (-6265 3410);
FORCEPROP 0 LASTPIN (-6275 5100) $PN 185
J 0
(-6265 5110);
DISPLAY 0.680851 (-6265 5110);
PAINT MONO (-6265 5110);
FORCEPROP 0 LASTPIN (-6275 3450) $PN 278
J 0
(-6265 3460);
DISPLAY 0.680851 (-6265 3460);
PAINT MONO (-6265 3460);
FORCEPROP 0 LASTPIN (-6275 5150) $PN 187
J 0
(-6265 5160);
DISPLAY 0.680851 (-6265 5160);
PAINT MONO (-6265 5160);
FORCEPROP 0 LASTPIN (-6275 3500) $PN 280
J 0
(-6265 3510);
DISPLAY 0.680851 (-6265 3510);
PAINT MONO (-6265 3510);
FORCEPROP 0 LASTPIN (-6275 5200) $PN 47
J 0
(-6265 5210);
DISPLAY 0.680851 (-6265 5210);
PAINT MONO (-6265 5210);
FORCEPROP 0 LASTPIN (-6275 3550) $PN 140
J 0
(-6265 3560);
DISPLAY 0.680851 (-6265 3560);
PAINT MONO (-6265 3560);
FORCEPROP 0 LASTPIN (-6275 5250) $PN 49
J 0
(-6265 5260);
DISPLAY 0.680851 (-6265 5260);
PAINT MONO (-6265 5260);
FORCEPROP 0 LASTPIN (-6275 3600) $PN 142
J 0
(-6265 3610);
DISPLAY 0.680851 (-6265 3610);
PAINT MONO (-6265 3610);
FORCEPROP 0 LASTPIN (-6275 5300) $PN 192
J 0
(-6265 5310);
DISPLAY 0.680851 (-6265 5310);
PAINT MONO (-6265 5310);
FORCEPROP 0 LASTPIN (-6275 3650) $PN 285
J 0
(-6265 3660);
DISPLAY 0.680851 (-6265 3660);
PAINT MONO (-6265 3660);
FORCEPROP 0 LASTPIN (-6275 5350) $PN 194
J 0
(-6265 5360);
DISPLAY 0.680851 (-6265 5360);
PAINT MONO (-6265 5360);
FORCEPROP 0 LASTPIN (-6275 3700) $PN 287
J 0
(-6265 3710);
DISPLAY 0.680851 (-6265 3710);
PAINT MONO (-6265 3710);
FORCEPROP 0 LASTPIN (-7475 2850) $PN 148
J 2
(-7485 2860);
DISPLAY 0.680851 (-7485 2860);
PAINT MONO (-7485 2860);
FORCEPROP 0 LASTPIN (-7475 2750) $PN 4
J 2
(-7485 2760);
DISPLAY 0.680851 (-7485 2760);
PAINT MONO (-7485 2760);
FORCEPROP 0 LASTPIN (-7475 2800) $PN 5
J 2
(-7485 2810);
DISPLAY 0.680851 (-7485 2810);
PAINT MONO (-7485 2810);
FORCEPROP 0 LASTPIN (-7475 1950) $PN 86
J 2
(-7485 1960);
DISPLAY 0.680851 (-7485 1960);
PAINT MONO (-7485 1960);
FORCEPROP 0 LASTPIN (-7475 1900) $PN 87
J 2
(-7485 1910);
DISPLAY 0.680851 (-7485 1910);
PAINT MONO (-7485 1910);
FORCEPROP 0 LASTPIN (-7475 4550) $PN 74
J 2
(-7485 4560);
DISPLAY 0.680851 (-7485 4560);
PAINT MONO (-7485 4560);
FORCEPROP 0 LASTPIN (-7475 4500) $PN 227
J 2
(-7485 4510);
DISPLAY 0.680851 (-7485 4510);
PAINT MONO (-7485 4510);
FORCEPROP 0 LASTPIN (-7475 2500) $PN 147
J 2
(-7485 2510);
DISPLAY 0.680851 (-7485 2510);
PAINT MONO (-7485 2510);
FORCEPROP 0 LASTPIN (-7475 3050) $PN 207
J 2
(-7485 3060);
DISPLAY 0.680851 (-7485 3060);
PAINT MONO (-7485 3060);
FORCEPROP 0 LASTPIN (-7475 2100) $PN 2
J 2
(-7485 2110);
DISPLAY 0.680851 (-7485 2110);
PAINT MONO (-7485 2110);
FORCEPROP 0 LASTPIN (-7475 2150) $PN 144
J 2
(-7485 2160);
DISPLAY 0.680851 (-7485 2160);
PAINT MONO (-7485 2160);
FORCEPROP 0 LASTPIN (-7475 2200) $PN 149
J 2
(-7485 2210);
DISPLAY 0.680851 (-7485 2210);
PAINT MONO (-7485 2210);
FORCEPROP 0 LASTPIN (-7475 2250) $PN 150
J 2
(-7485 2260);
DISPLAY 0.680851 (-7485 2260);
PAINT MONO (-7485 2260);
FORCEPROP 0 LASTPIN (-7475 2300) $PN 220
J 2
(-7485 2310);
DISPLAY 0.680851 (-7485 2310);
PAINT MONO (-7485 2310);
FORCEPROP 0 LASTPIN (-7475 2350) $PN 231
J 2
(-7485 2360);
DISPLAY 0.680851 (-7485 2360);
PAINT MONO (-7485 2360);
FORCEPROP 0 LASTPIN (-7475 2400) $PN 232
J 2
(-7485 2410);
DISPLAY 0.680851 (-7485 2410);
PAINT MONO (-7485 2410);
FORCEPROP 0 LASTPIN (-7475 2900) $PN 3
J 2
(-7485 2910);
DISPLAY 0.680851 (-7485 2910);
PAINT MONO (-7485 2910);
FORCEPROP 2 LAST VALUE SCONN288_DDR506112002KQ
J 0
(-7325 5725);
DISPLAY 0.489362 (-7325 5725);
PAINT SKYBLUE (-7325 5725);
FORCEPROP 1 LAST MATERIAL IO
J 0
(-7325 5525);
DISPLAY 0.468085 (-7325 5525);
PAINT SKYBLUE (-7325 5525);
FORCEPROP 2 LAST PART_TYPE SMLF
J 0
(-7325 5775);
DISPLAY 1.021277 (-7325 5775);
FORCEPROP 2 LAST CDS_LIB pure_quanta
J 0
(-6875 3600);
DISPLAY INVISIBLE (-6875 3600);
FORCEPROP 1 LAST NEEDS_NO_SIZE TRUE
J 0
(-6875 3600);
DISPLAY 0.723404 (-6875 3600);
PAINT GREEN (-6875 3600);
DISPLAY INVISIBLE (-6875 3600);
FORCEPROP 1 LAST CDS_LMAN_SYM_OUTLINE -450,1900,450,-1850
J 0
(-6875 3600);
DISPLAY 0.468085 (-6875 3600);
PAINT GREEN (-6875 3600);
DISPLAY INVISIBLE (-6875 3600);
FORCEPROP 1 LAST PATH I22
J 0
(-6875 3600);
DISPLAY 0.723404 (-6875 3600);
PAINT GREEN (-6875 3600);
DISPLAY INVISIBLE (-6875 3600);
FORCEPROP 1 LAST PART_NUMBER DFHST8FS479
J 0
(-7325 5600);
DISPLAY 0.468085 (-7325 5600);
PAINT SKYBLUE (-7325 5600);
DISPLAY INVISIBLE (-7325 5600);
FORCEADD TAP..1
(-3500 3300);
FORCEPROP 3 LASTPIN (-3550 3300) SIG_NAME M_H_CPU0_SB_DQS_DP<9>
J 0
(-3540 3310);
DISPLAY 0.659574 (-3540 3310);
PAINT MONO (-3540 3310);
DISPLAY INVISIBLE (-3540 3310);
FORCEPROP 1 LASTPIN (-3550 3300) BN 9
J 0
(-3562 3308);
DISPLAY 0.489362 (-3562 3308);
PAINT GREEN (-3562 3308);
FORCEPROP 2 LAST CDS_LIB mstr_standard
J 0
(-3500 3300);
DISPLAY 0.723404 (-3500 3300);
PAINT MONO (-3500 3300);
DISPLAY INVISIBLE (-3500 3300);
FORCEPROP 1 LAST BODY_TYPE PLUMBING
J 0
(-3500 3350);
DISPLAY 0.872340 (-3500 3350);
PAINT GREEN (-3500 3350);
DISPLAY INVISIBLE (-3500 3350);
FORCEPROP 1 LAST HDL_TAP TRUE
J 0
(-3175 3175);
DISPLAY 0.872340 (-3175 3175);
DISPLAY INVISIBLE (-3175 3175);
FORCEPROP 1 LAST PATH I220
J 0
(-3502 3300);
DISPLAY 0.872340 (-3502 3300);
PAINT GREEN (-3502 3300);
DISPLAY INVISIBLE (-3502 3300);
FORCEADD TAP..1
(-3300 3050);
FORCEPROP 3 LASTPIN (-3350 3050) SIG_NAME M_H_CPU0_SB_DQS_DN<7>
J 0
(-3340 3060);
DISPLAY 0.659574 (-3340 3060);
PAINT MONO (-3340 3060);
DISPLAY INVISIBLE (-3340 3060);
FORCEPROP 1 LASTPIN (-3350 3050) BN 7
J 0
(-3362 3058);
DISPLAY 0.489362 (-3362 3058);
PAINT GREEN (-3362 3058);
FORCEPROP 2 LAST CDS_LIB mstr_standard
J 0
(-3300 3050);
DISPLAY 0.723404 (-3300 3050);
PAINT MONO (-3300 3050);
DISPLAY INVISIBLE (-3300 3050);
FORCEPROP 1 LAST BODY_TYPE PLUMBING
J 0
(-3300 3100);
DISPLAY 0.872340 (-3300 3100);
PAINT GREEN (-3300 3100);
DISPLAY INVISIBLE (-3300 3100);
FORCEPROP 1 LAST HDL_TAP TRUE
J 0
(-2975 2925);
DISPLAY 0.872340 (-2975 2925);
DISPLAY INVISIBLE (-2975 2925);
FORCEPROP 1 LAST PATH I221
J 0
(-3302 3050);
DISPLAY 0.872340 (-3302 3050);
PAINT GREEN (-3302 3050);
DISPLAY INVISIBLE (-3302 3050);
FORCEADD TAP..1
(-3300 2950);
FORCEPROP 3 LASTPIN (-3350 2950) SIG_NAME M_H_CPU0_SB_DQS_DN<6>
J 0
(-3340 2960);
DISPLAY 0.659574 (-3340 2960);
PAINT MONO (-3340 2960);
DISPLAY INVISIBLE (-3340 2960);
FORCEPROP 1 LASTPIN (-3350 2950) BN 6
J 0
(-3362 2958);
DISPLAY 0.489362 (-3362 2958);
PAINT GREEN (-3362 2958);
FORCEPROP 2 LAST CDS_LIB mstr_standard
J 0
(-3300 2950);
DISPLAY 0.723404 (-3300 2950);
PAINT MONO (-3300 2950);
DISPLAY INVISIBLE (-3300 2950);
FORCEPROP 1 LAST BODY_TYPE PLUMBING
J 0
(-3300 3000);
DISPLAY 0.872340 (-3300 3000);
PAINT GREEN (-3300 3000);
DISPLAY INVISIBLE (-3300 3000);
FORCEPROP 1 LAST HDL_TAP TRUE
J 0
(-2975 2825);
DISPLAY 0.872340 (-2975 2825);
DISPLAY INVISIBLE (-2975 2825);
FORCEPROP 1 LAST PATH I222
J 0
(-3302 2950);
DISPLAY 0.872340 (-3302 2950);
PAINT GREEN (-3302 2950);
DISPLAY INVISIBLE (-3302 2950);
FORCEADD TAP..1
(-3300 2850);
FORCEPROP 3 LASTPIN (-3350 2850) SIG_NAME M_H_CPU0_SB_DQS_DN<5>
J 0
(-3340 2860);
DISPLAY 0.659574 (-3340 2860);
PAINT MONO (-3340 2860);
DISPLAY INVISIBLE (-3340 2860);
FORCEPROP 1 LASTPIN (-3350 2850) BN 5
J 0
(-3362 2858);
DISPLAY 0.489362 (-3362 2858);
PAINT GREEN (-3362 2858);
FORCEPROP 2 LAST CDS_LIB mstr_standard
J 0
(-3300 2850);
DISPLAY 0.723404 (-3300 2850);
PAINT MONO (-3300 2850);
DISPLAY INVISIBLE (-3300 2850);
FORCEPROP 1 LAST BODY_TYPE PLUMBING
J 0
(-3300 2900);
DISPLAY 0.872340 (-3300 2900);
PAINT GREEN (-3300 2900);
DISPLAY INVISIBLE (-3300 2900);
FORCEPROP 1 LAST HDL_TAP TRUE
J 0
(-2975 2725);
DISPLAY 0.872340 (-2975 2725);
DISPLAY INVISIBLE (-2975 2725);
FORCEPROP 1 LAST PATH I223
J 0
(-3302 2850);
DISPLAY 0.872340 (-3302 2850);
PAINT GREEN (-3302 2850);
DISPLAY INVISIBLE (-3302 2850);
FORCEADD TAP..1
(-3300 2650);
FORCEPROP 3 LASTPIN (-3350 2650) SIG_NAME M_H_CPU0_SB_DQS_DN<3>
J 0
(-3340 2660);
DISPLAY 0.659574 (-3340 2660);
PAINT MONO (-3340 2660);
DISPLAY INVISIBLE (-3340 2660);
FORCEPROP 1 LASTPIN (-3350 2650) BN 3
J 0
(-3362 2658);
DISPLAY 0.489362 (-3362 2658);
PAINT GREEN (-3362 2658);
FORCEPROP 2 LAST CDS_LIB mstr_standard
J 0
(-3300 2650);
DISPLAY 0.723404 (-3300 2650);
PAINT MONO (-3300 2650);
DISPLAY INVISIBLE (-3300 2650);
FORCEPROP 1 LAST BODY_TYPE PLUMBING
J 0
(-3300 2700);
DISPLAY 0.872340 (-3300 2700);
PAINT GREEN (-3300 2700);
DISPLAY INVISIBLE (-3300 2700);
FORCEPROP 1 LAST HDL_TAP TRUE
J 0
(-2975 2525);
DISPLAY 0.872340 (-2975 2525);
DISPLAY INVISIBLE (-2975 2525);
FORCEPROP 1 LAST PATH I224
J 0
(-3302 2650);
DISPLAY 0.872340 (-3302 2650);
PAINT GREEN (-3302 2650);
DISPLAY INVISIBLE (-3302 2650);
FORCEADD TAP..1
(-3300 2750);
FORCEPROP 3 LASTPIN (-3350 2750) SIG_NAME M_H_CPU0_SB_DQS_DN<4>
J 0
(-3340 2760);
DISPLAY 0.659574 (-3340 2760);
PAINT MONO (-3340 2760);
DISPLAY INVISIBLE (-3340 2760);
FORCEPROP 1 LASTPIN (-3350 2750) BN 4
J 0
(-3362 2758);
DISPLAY 0.489362 (-3362 2758);
PAINT GREEN (-3362 2758);
FORCEPROP 2 LAST CDS_LIB mstr_standard
J 0
(-3300 2750);
DISPLAY 0.723404 (-3300 2750);
PAINT MONO (-3300 2750);
DISPLAY INVISIBLE (-3300 2750);
FORCEPROP 1 LAST BODY_TYPE PLUMBING
J 0
(-3300 2800);
DISPLAY 0.872340 (-3300 2800);
PAINT GREEN (-3300 2800);
DISPLAY INVISIBLE (-3300 2800);
FORCEPROP 1 LAST HDL_TAP TRUE
J 0
(-2975 2625);
DISPLAY 0.872340 (-2975 2625);
DISPLAY INVISIBLE (-2975 2625);
FORCEPROP 1 LAST PATH I225
J 0
(-3302 2750);
DISPLAY 0.872340 (-3302 2750);
PAINT GREEN (-3302 2750);
DISPLAY INVISIBLE (-3302 2750);
FORCEADD TAP..1
(-3500 2900);
FORCEPROP 3 LASTPIN (-3550 2900) SIG_NAME M_H_CPU0_SB_DQS_DP<5>
J 0
(-3540 2910);
DISPLAY 0.659574 (-3540 2910);
PAINT MONO (-3540 2910);
DISPLAY INVISIBLE (-3540 2910);
FORCEPROP 1 LASTPIN (-3550 2900) BN 5
J 0
(-3562 2908);
DISPLAY 0.489362 (-3562 2908);
PAINT GREEN (-3562 2908);
FORCEPROP 2 LAST CDS_LIB mstr_standard
J 0
(-3500 2900);
DISPLAY 0.723404 (-3500 2900);
PAINT MONO (-3500 2900);
DISPLAY INVISIBLE (-3500 2900);
FORCEPROP 1 LAST BODY_TYPE PLUMBING
J 0
(-3500 2950);
DISPLAY 0.872340 (-3500 2950);
PAINT GREEN (-3500 2950);
DISPLAY INVISIBLE (-3500 2950);
FORCEPROP 1 LAST HDL_TAP TRUE
J 0
(-3175 2775);
DISPLAY 0.872340 (-3175 2775);
DISPLAY INVISIBLE (-3175 2775);
FORCEPROP 1 LAST PATH I226
J 0
(-3502 2900);
DISPLAY 0.872340 (-3502 2900);
PAINT GREEN (-3502 2900);
DISPLAY INVISIBLE (-3502 2900);
FORCEADD TAP..1
(-3500 3100);
FORCEPROP 3 LASTPIN (-3550 3100) SIG_NAME M_H_CPU0_SB_DQS_DP<7>
J 0
(-3540 3110);
DISPLAY 0.659574 (-3540 3110);
PAINT MONO (-3540 3110);
DISPLAY INVISIBLE (-3540 3110);
FORCEPROP 1 LASTPIN (-3550 3100) BN 7
J 0
(-3562 3108);
DISPLAY 0.489362 (-3562 3108);
PAINT GREEN (-3562 3108);
FORCEPROP 2 LAST CDS_LIB mstr_standard
J 0
(-3500 3100);
DISPLAY 0.723404 (-3500 3100);
PAINT MONO (-3500 3100);
DISPLAY INVISIBLE (-3500 3100);
FORCEPROP 1 LAST BODY_TYPE PLUMBING
J 0
(-3500 3150);
DISPLAY 0.872340 (-3500 3150);
PAINT GREEN (-3500 3150);
DISPLAY INVISIBLE (-3500 3150);
FORCEPROP 1 LAST HDL_TAP TRUE
J 0
(-3175 2975);
DISPLAY 0.872340 (-3175 2975);
DISPLAY INVISIBLE (-3175 2975);
FORCEPROP 1 LAST PATH I227
J 0
(-3502 3100);
DISPLAY 0.872340 (-3502 3100);
PAINT GREEN (-3502 3100);
DISPLAY INVISIBLE (-3502 3100);
FORCEADD TAP..1
(-3500 3000);
FORCEPROP 3 LASTPIN (-3550 3000) SIG_NAME M_H_CPU0_SB_DQS_DP<6>
J 0
(-3540 3010);
DISPLAY 0.659574 (-3540 3010);
PAINT MONO (-3540 3010);
DISPLAY INVISIBLE (-3540 3010);
FORCEPROP 1 LASTPIN (-3550 3000) BN 6
J 0
(-3562 3008);
DISPLAY 0.489362 (-3562 3008);
PAINT GREEN (-3562 3008);
FORCEPROP 2 LAST CDS_LIB mstr_standard
J 0
(-3500 3000);
DISPLAY 0.723404 (-3500 3000);
PAINT MONO (-3500 3000);
DISPLAY INVISIBLE (-3500 3000);
FORCEPROP 1 LAST BODY_TYPE PLUMBING
J 0
(-3500 3050);
DISPLAY 0.872340 (-3500 3050);
PAINT GREEN (-3500 3050);
DISPLAY INVISIBLE (-3500 3050);
FORCEPROP 1 LAST HDL_TAP TRUE
J 0
(-3175 2875);
DISPLAY 0.872340 (-3175 2875);
DISPLAY INVISIBLE (-3175 2875);
FORCEPROP 1 LAST PATH I228
J 0
(-3502 3000);
DISPLAY 0.872340 (-3502 3000);
PAINT GREEN (-3502 3000);
DISPLAY INVISIBLE (-3502 3000);
FORCEADD TAP..1
(-3500 2800);
FORCEPROP 3 LASTPIN (-3550 2800) SIG_NAME M_H_CPU0_SB_DQS_DP<4>
J 0
(-3540 2810);
DISPLAY 0.659574 (-3540 2810);
PAINT MONO (-3540 2810);
DISPLAY INVISIBLE (-3540 2810);
FORCEPROP 1 LASTPIN (-3550 2800) BN 4
J 0
(-3562 2808);
DISPLAY 0.489362 (-3562 2808);
PAINT GREEN (-3562 2808);
FORCEPROP 2 LAST CDS_LIB mstr_standard
J 0
(-3500 2800);
DISPLAY 0.723404 (-3500 2800);
PAINT MONO (-3500 2800);
DISPLAY INVISIBLE (-3500 2800);
FORCEPROP 1 LAST BODY_TYPE PLUMBING
J 0
(-3500 2850);
DISPLAY 0.872340 (-3500 2850);
PAINT GREEN (-3500 2850);
DISPLAY INVISIBLE (-3500 2850);
FORCEPROP 1 LAST HDL_TAP TRUE
J 0
(-3175 2675);
DISPLAY 0.872340 (-3175 2675);
DISPLAY INVISIBLE (-3175 2675);
FORCEPROP 1 LAST PATH I229
J 0
(-3502 2800);
DISPLAY 0.872340 (-3502 2800);
PAINT GREEN (-3502 2800);
DISPLAY INVISIBLE (-3502 2800);
FORCEADD TAP..1
R 2
(-7725 3150);
FORCEPROP 3 LASTPIN (-7675 3150) SIG_NAME M_H_CPU0_SB_CB<0>
J 0
(-7665 3160);
DISPLAY 0.659574 (-7665 3160);
PAINT MONO (-7665 3160);
DISPLAY INVISIBLE (-7665 3160);
FORCEPROP 1 LASTPIN (-7675 3150) BN 0
J 2
(-7663 3158);
DISPLAY 0.489362 (-7663 3158);
PAINT GREEN (-7663 3158);
FORCEPROP 2 LAST CDS_LIB mstr_standard
J 0
(-7725 3150);
DISPLAY 0.723404 (-7725 3150);
PAINT MONO (-7725 3150);
DISPLAY INVISIBLE (-7725 3150);
FORCEPROP 1 LAST BODY_TYPE PLUMBING
J 2
(-7725 3200);
DISPLAY 0.872340 (-7725 3200);
PAINT GREEN (-7725 3200);
DISPLAY INVISIBLE (-7725 3200);
FORCEPROP 1 LAST HDL_TAP TRUE
J 2
(-8050 3025);
DISPLAY 0.872340 (-8050 3025);
DISPLAY INVISIBLE (-8050 3025);
FORCEPROP 1 LAST PATH I23
J 2
(-7723 3150);
DISPLAY 0.872340 (-7723 3150);
PAINT GREEN (-7723 3150);
DISPLAY INVISIBLE (-7723 3150);
FORCEADD TAP..1
(-3500 2700);
FORCEPROP 3 LASTPIN (-3550 2700) SIG_NAME M_H_CPU0_SB_DQS_DP<3>
J 0
(-3540 2710);
DISPLAY 0.659574 (-3540 2710);
PAINT MONO (-3540 2710);
DISPLAY INVISIBLE (-3540 2710);
FORCEPROP 1 LASTPIN (-3550 2700) BN 3
J 0
(-3562 2708);
DISPLAY 0.489362 (-3562 2708);
PAINT GREEN (-3562 2708);
FORCEPROP 2 LAST CDS_LIB mstr_standard
J 0
(-3500 2700);
DISPLAY 0.723404 (-3500 2700);
PAINT MONO (-3500 2700);
DISPLAY INVISIBLE (-3500 2700);
FORCEPROP 1 LAST BODY_TYPE PLUMBING
J 0
(-3500 2750);
DISPLAY 0.872340 (-3500 2750);
PAINT GREEN (-3500 2750);
DISPLAY INVISIBLE (-3500 2750);
FORCEPROP 1 LAST HDL_TAP TRUE
J 0
(-3175 2575);
DISPLAY 0.872340 (-3175 2575);
DISPLAY INVISIBLE (-3175 2575);
FORCEPROP 1 LAST PATH I230
J 0
(-3502 2700);
DISPLAY 0.872340 (-3502 2700);
PAINT GREEN (-3502 2700);
DISPLAY INVISIBLE (-3502 2700);
FORCEADD TAP..1
(-3300 2550);
FORCEPROP 3 LASTPIN (-3350 2550) SIG_NAME M_H_CPU0_SB_DQS_DN<2>
J 0
(-3340 2560);
DISPLAY 0.659574 (-3340 2560);
PAINT MONO (-3340 2560);
DISPLAY INVISIBLE (-3340 2560);
FORCEPROP 1 LASTPIN (-3350 2550) BN 2
J 0
(-3362 2558);
DISPLAY 0.489362 (-3362 2558);
PAINT GREEN (-3362 2558);
FORCEPROP 2 LAST CDS_LIB mstr_standard
J 0
(-3300 2550);
DISPLAY 0.723404 (-3300 2550);
PAINT MONO (-3300 2550);
DISPLAY INVISIBLE (-3300 2550);
FORCEPROP 1 LAST BODY_TYPE PLUMBING
J 0
(-3300 2600);
DISPLAY 0.872340 (-3300 2600);
PAINT GREEN (-3300 2600);
DISPLAY INVISIBLE (-3300 2600);
FORCEPROP 1 LAST HDL_TAP TRUE
J 0
(-2975 2425);
DISPLAY 0.872340 (-2975 2425);
DISPLAY INVISIBLE (-2975 2425);
FORCEPROP 1 LAST PATH I231
J 0
(-3302 2550);
DISPLAY 0.872340 (-3302 2550);
PAINT GREEN (-3302 2550);
DISPLAY INVISIBLE (-3302 2550);
FORCEADD TAP..1
(-3300 2450);
FORCEPROP 3 LASTPIN (-3350 2450) SIG_NAME M_H_CPU0_SB_DQS_DN<1>
J 0
(-3340 2460);
DISPLAY 0.659574 (-3340 2460);
PAINT MONO (-3340 2460);
DISPLAY INVISIBLE (-3340 2460);
FORCEPROP 1 LASTPIN (-3350 2450) BN 1
J 0
(-3362 2458);
DISPLAY 0.489362 (-3362 2458);
PAINT GREEN (-3362 2458);
FORCEPROP 2 LAST CDS_LIB mstr_standard
J 0
(-3300 2450);
DISPLAY 0.723404 (-3300 2450);
PAINT MONO (-3300 2450);
DISPLAY INVISIBLE (-3300 2450);
FORCEPROP 1 LAST BODY_TYPE PLUMBING
J 0
(-3300 2500);
DISPLAY 0.872340 (-3300 2500);
PAINT GREEN (-3300 2500);
DISPLAY INVISIBLE (-3300 2500);
FORCEPROP 1 LAST HDL_TAP TRUE
J 0
(-2975 2325);
DISPLAY 0.872340 (-2975 2325);
DISPLAY INVISIBLE (-2975 2325);
FORCEPROP 1 LAST PATH I232
J 0
(-3302 2450);
DISPLAY 0.872340 (-3302 2450);
PAINT GREEN (-3302 2450);
DISPLAY INVISIBLE (-3302 2450);
FORCEADD TAP..1
(-3300 2350);
FORCEPROP 3 LASTPIN (-3350 2350) SIG_NAME M_H_CPU0_SB_DQS_DN<0>
J 0
(-3340 2360);
DISPLAY 0.659574 (-3340 2360);
PAINT MONO (-3340 2360);
DISPLAY INVISIBLE (-3340 2360);
FORCEPROP 1 LASTPIN (-3350 2350) BN 0
J 0
(-3362 2358);
DISPLAY 0.489362 (-3362 2358);
PAINT GREEN (-3362 2358);
FORCEPROP 2 LAST CDS_LIB mstr_standard
J 0
(-3300 2350);
DISPLAY 0.723404 (-3300 2350);
PAINT MONO (-3300 2350);
DISPLAY INVISIBLE (-3300 2350);
FORCEPROP 1 LAST BODY_TYPE PLUMBING
J 0
(-3300 2400);
DISPLAY 0.872340 (-3300 2400);
PAINT GREEN (-3300 2400);
DISPLAY INVISIBLE (-3300 2400);
FORCEPROP 1 LAST HDL_TAP TRUE
J 0
(-2975 2225);
DISPLAY 0.872340 (-2975 2225);
DISPLAY INVISIBLE (-2975 2225);
FORCEPROP 1 LAST PATH I233
J 0
(-3302 2350);
DISPLAY 0.872340 (-3302 2350);
PAINT GREEN (-3302 2350);
DISPLAY INVISIBLE (-3302 2350);
FORCEADD TAP..1
(-3500 2400);
FORCEPROP 3 LASTPIN (-3550 2400) SIG_NAME M_H_CPU0_SB_DQS_DP<0>
J 0
(-3540 2410);
DISPLAY 0.659574 (-3540 2410);
PAINT MONO (-3540 2410);
DISPLAY INVISIBLE (-3540 2410);
FORCEPROP 1 LASTPIN (-3550 2400) BN 0
J 0
(-3562 2408);
DISPLAY 0.489362 (-3562 2408);
PAINT GREEN (-3562 2408);
FORCEPROP 2 LAST CDS_LIB mstr_standard
J 0
(-3500 2400);
DISPLAY 0.723404 (-3500 2400);
PAINT MONO (-3500 2400);
DISPLAY INVISIBLE (-3500 2400);
FORCEPROP 1 LAST BODY_TYPE PLUMBING
J 0
(-3500 2450);
DISPLAY 0.872340 (-3500 2450);
PAINT GREEN (-3500 2450);
DISPLAY INVISIBLE (-3500 2450);
FORCEPROP 1 LAST HDL_TAP TRUE
J 0
(-3175 2275);
DISPLAY 0.872340 (-3175 2275);
DISPLAY INVISIBLE (-3175 2275);
FORCEPROP 1 LAST PATH I234
J 0
(-3502 2400);
DISPLAY 0.872340 (-3502 2400);
PAINT GREEN (-3502 2400);
DISPLAY INVISIBLE (-3502 2400);
FORCEADD TAP..1
(-3500 2500);
FORCEPROP 3 LASTPIN (-3550 2500) SIG_NAME M_H_CPU0_SB_DQS_DP<1>
J 0
(-3540 2510);
DISPLAY 0.659574 (-3540 2510);
PAINT MONO (-3540 2510);
DISPLAY INVISIBLE (-3540 2510);
FORCEPROP 1 LASTPIN (-3550 2500) BN 1
J 0
(-3562 2508);
DISPLAY 0.489362 (-3562 2508);
PAINT GREEN (-3562 2508);
FORCEPROP 2 LAST CDS_LIB mstr_standard
J 0
(-3500 2500);
DISPLAY 0.723404 (-3500 2500);
PAINT MONO (-3500 2500);
DISPLAY INVISIBLE (-3500 2500);
FORCEPROP 1 LAST BODY_TYPE PLUMBING
J 0
(-3500 2550);
DISPLAY 0.872340 (-3500 2550);
PAINT GREEN (-3500 2550);
DISPLAY INVISIBLE (-3500 2550);
FORCEPROP 1 LAST HDL_TAP TRUE
J 0
(-3175 2375);
DISPLAY 0.872340 (-3175 2375);
DISPLAY INVISIBLE (-3175 2375);
FORCEPROP 1 LAST PATH I235
J 0
(-3502 2500);
DISPLAY 0.872340 (-3502 2500);
PAINT GREEN (-3502 2500);
DISPLAY INVISIBLE (-3502 2500);
FORCEADD TAP..1
(-3500 2600);
FORCEPROP 3 LASTPIN (-3550 2600) SIG_NAME M_H_CPU0_SB_DQS_DP<2>
J 0
(-3540 2610);
DISPLAY 0.659574 (-3540 2610);
PAINT MONO (-3540 2610);
DISPLAY INVISIBLE (-3540 2610);
FORCEPROP 1 LASTPIN (-3550 2600) BN 2
J 0
(-3562 2608);
DISPLAY 0.489362 (-3562 2608);
PAINT GREEN (-3562 2608);
FORCEPROP 2 LAST CDS_LIB mstr_standard
J 0
(-3500 2600);
DISPLAY 0.723404 (-3500 2600);
PAINT MONO (-3500 2600);
DISPLAY INVISIBLE (-3500 2600);
FORCEPROP 1 LAST BODY_TYPE PLUMBING
J 0
(-3500 2650);
DISPLAY 0.872340 (-3500 2650);
PAINT GREEN (-3500 2650);
DISPLAY INVISIBLE (-3500 2650);
FORCEPROP 1 LAST HDL_TAP TRUE
J 0
(-3175 2475);
DISPLAY 0.872340 (-3175 2475);
DISPLAY INVISIBLE (-3175 2475);
FORCEPROP 1 LAST PATH I236
J 0
(-3502 2600);
DISPLAY 0.872340 (-3502 2600);
PAINT GREEN (-3502 2600);
DISPLAY INVISIBLE (-3502 2600);
FORCEADD SCONN288_DDR506112002KQ..2
(-4450 3350);
FORCEPROP 1 LAST LOCATION J69
J 0
(-5050 4675);
DISPLAY 0.468085 (-5050 4675);
PAINT SKYBLUE (-5050 4675);
FORCEPROP 0 LAST $SEC 2
J 0
(-4900 4825);
DISPLAY 0.680851 (-4900 4825);
PAINT MONO (-4900 4825);
DISPLAY INVISIBLE (-4900 4825);
FORCEPROP 0 LAST CDS_SEC 2
J 0
(-4900 4825);
DISPLAY 1.021277 (-4900 4825);
DISPLAY INVISIBLE (-4900 4825);
FORCEPROP 0 LASTPIN (-3700 3400) $PN 12
J 0
(-3690 3410);
DISPLAY 0.680851 (-3690 3410);
PAINT MONO (-3690 3410);
FORCEPROP 0 LASTPIN (-3700 3450) $PN 11
J 0
(-3690 3460);
DISPLAY 0.680851 (-3690 3460);
PAINT MONO (-3690 3460);
FORCEPROP 0 LASTPIN (-3700 2350) $PN 105
J 0
(-3690 2360);
DISPLAY 0.680851 (-3690 2360);
PAINT MONO (-3690 2360);
FORCEPROP 0 LASTPIN (-3700 2400) $PN 104
J 0
(-3690 2410);
DISPLAY 0.680851 (-3690 2410);
PAINT MONO (-3690 2410);
FORCEPROP 0 LASTPIN (-3700 3500) $PN 23
J 0
(-3690 3510);
DISPLAY 0.680851 (-3690 3510);
PAINT MONO (-3690 3510);
FORCEPROP 0 LASTPIN (-3700 3550) $PN 22
J 0
(-3690 3560);
DISPLAY 0.680851 (-3690 3560);
PAINT MONO (-3690 3560);
FORCEPROP 0 LASTPIN (-3700 2450) $PN 116
J 0
(-3690 2460);
DISPLAY 0.680851 (-3690 2460);
PAINT MONO (-3690 2460);
FORCEPROP 0 LASTPIN (-3700 2500) $PN 115
J 0
(-3690 2510);
DISPLAY 0.680851 (-3690 2510);
PAINT MONO (-3690 2510);
FORCEPROP 0 LASTPIN (-3700 3600) $PN 34
J 0
(-3690 3610);
DISPLAY 0.680851 (-3690 3610);
PAINT MONO (-3690 3610);
FORCEPROP 0 LASTPIN (-3700 3650) $PN 33
J 0
(-3690 3660);
DISPLAY 0.680851 (-3690 3660);
PAINT MONO (-3690 3660);
FORCEPROP 0 LASTPIN (-3700 2550) $PN 127
J 0
(-3690 2560);
DISPLAY 0.680851 (-3690 2560);
PAINT MONO (-3690 2560);
FORCEPROP 0 LASTPIN (-3700 2600) $PN 126
J 0
(-3690 2610);
DISPLAY 0.680851 (-3690 2610);
PAINT MONO (-3690 2610);
FORCEPROP 0 LASTPIN (-3700 3700) $PN 45
J 0
(-3690 3710);
DISPLAY 0.680851 (-3690 3710);
PAINT MONO (-3690 3710);
FORCEPROP 0 LASTPIN (-3700 3750) $PN 44
J 0
(-3690 3760);
DISPLAY 0.680851 (-3690 3760);
PAINT MONO (-3690 3760);
FORCEPROP 0 LASTPIN (-3700 2650) $PN 138
J 0
(-3690 2660);
DISPLAY 0.680851 (-3690 2660);
PAINT MONO (-3690 2660);
FORCEPROP 0 LASTPIN (-3700 2700) $PN 137
J 0
(-3690 2710);
DISPLAY 0.680851 (-3690 2710);
PAINT MONO (-3690 2710);
FORCEPROP 0 LASTPIN (-3700 3800) $PN 56
J 0
(-3690 3810);
DISPLAY 0.680851 (-3690 3810);
PAINT MONO (-3690 3810);
FORCEPROP 0 LASTPIN (-3700 3850) $PN 55
J 0
(-3690 3860);
DISPLAY 0.680851 (-3690 3860);
PAINT MONO (-3690 3860);
FORCEPROP 0 LASTPIN (-3700 2750) $PN 238
J 0
(-3690 2760);
DISPLAY 0.680851 (-3690 2760);
PAINT MONO (-3690 2760);
FORCEPROP 0 LASTPIN (-3700 2800) $PN 239
J 0
(-3690 2810);
DISPLAY 0.680851 (-3690 2810);
PAINT MONO (-3690 2810);
FORCEPROP 0 LASTPIN (-3700 3900) $PN 156
J 0
(-3690 3910);
DISPLAY 0.680851 (-3690 3910);
PAINT MONO (-3690 3910);
FORCEPROP 0 LASTPIN (-3700 3950) $PN 157
J 0
(-3690 3960);
DISPLAY 0.680851 (-3690 3960);
PAINT MONO (-3690 3960);
FORCEPROP 0 LASTPIN (-3700 2850) $PN 249
J 0
(-3690 2860);
DISPLAY 0.680851 (-3690 2860);
PAINT MONO (-3690 2860);
FORCEPROP 0 LASTPIN (-3700 2900) $PN 250
J 0
(-3690 2910);
DISPLAY 0.680851 (-3690 2910);
PAINT MONO (-3690 2910);
FORCEPROP 0 LASTPIN (-3700 4000) $PN 167
J 0
(-3690 4010);
DISPLAY 0.680851 (-3690 4010);
PAINT MONO (-3690 4010);
FORCEPROP 0 LASTPIN (-3700 4050) $PN 168
J 0
(-3690 4060);
DISPLAY 0.680851 (-3690 4060);
PAINT MONO (-3690 4060);
FORCEPROP 0 LASTPIN (-3700 2950) $PN 260
J 0
(-3690 2960);
DISPLAY 0.680851 (-3690 2960);
PAINT MONO (-3690 2960);
FORCEPROP 0 LASTPIN (-3700 3000) $PN 261
J 0
(-3690 3010);
DISPLAY 0.680851 (-3690 3010);
PAINT MONO (-3690 3010);
FORCEPROP 0 LASTPIN (-3700 4100) $PN 178
J 0
(-3690 4110);
DISPLAY 0.680851 (-3690 4110);
PAINT MONO (-3690 4110);
FORCEPROP 0 LASTPIN (-3700 4150) $PN 179
J 0
(-3690 4160);
DISPLAY 0.680851 (-3690 4160);
PAINT MONO (-3690 4160);
FORCEPROP 0 LASTPIN (-3700 3050) $PN 271
J 0
(-3690 3060);
DISPLAY 0.680851 (-3690 3060);
PAINT MONO (-3690 3060);
FORCEPROP 0 LASTPIN (-3700 3100) $PN 272
J 0
(-3690 3110);
DISPLAY 0.680851 (-3690 3110);
PAINT MONO (-3690 3110);
FORCEPROP 0 LASTPIN (-3700 4200) $PN 189
J 0
(-3690 4210);
DISPLAY 0.680851 (-3690 4210);
PAINT MONO (-3690 4210);
FORCEPROP 0 LASTPIN (-3700 4250) $PN 190
J 0
(-3690 4260);
DISPLAY 0.680851 (-3690 4260);
PAINT MONO (-3690 4260);
FORCEPROP 0 LASTPIN (-3700 3150) $PN 282
J 0
(-3690 3160);
DISPLAY 0.680851 (-3690 3160);
PAINT MONO (-3690 3160);
FORCEPROP 0 LASTPIN (-3700 3200) $PN 283
J 0
(-3690 3210);
DISPLAY 0.680851 (-3690 3210);
PAINT MONO (-3690 3210);
FORCEPROP 0 LASTPIN (-3700 4300) $PN 200
J 0
(-3690 4310);
DISPLAY 0.680851 (-3690 4310);
PAINT MONO (-3690 4310);
FORCEPROP 0 LASTPIN (-3700 4350) $PN 201
J 0
(-3690 4360);
DISPLAY 0.680851 (-3690 4360);
PAINT MONO (-3690 4360);
FORCEPROP 0 LASTPIN (-3700 3250) $PN 94
J 0
(-3690 3260);
DISPLAY 0.680851 (-3690 3260);
PAINT MONO (-3690 3260);
FORCEPROP 0 LASTPIN (-3700 3300) $PN 93
J 0
(-3690 3310);
DISPLAY 0.680851 (-3690 3310);
PAINT MONO (-3690 3310);
FORCEPROP 2 LAST PART_TYPE SMLF
J 0
(-4900 4775);
DISPLAY 1.021277 (-4900 4775);
FORCEPROP 2 LAST VALUE SCONN288_DDR506112002KQ
J 0
(-4900 4725);
DISPLAY 0.489362 (-4900 4725);
PAINT SKYBLUE (-4900 4725);
FORCEPROP 1 LAST MATERIAL IO
J 0
(-5050 4525);
DISPLAY 0.468085 (-5050 4525);
PAINT SKYBLUE (-5050 4525);
FORCEPROP 2 LAST CDS_LIB pure_quanta
J 0
(-4450 3350);
DISPLAY INVISIBLE (-4450 3350);
FORCEPROP 1 LAST NEEDS_NO_SIZE TRUE
J 0
(-4450 3350);
DISPLAY 0.723404 (-4450 3350);
PAINT GREEN (-4450 3350);
DISPLAY INVISIBLE (-4450 3350);
FORCEPROP 1 LAST CDS_LMAN_SYM_OUTLINE -600,1150,600,-1150
J 0
(-4450 3350);
DISPLAY 0.468085 (-4450 3350);
PAINT GREEN (-4450 3350);
DISPLAY INVISIBLE (-4450 3350);
FORCEPROP 1 LAST PATH I237
J 0
(-4450 3350);
DISPLAY 0.723404 (-4450 3350);
PAINT GREEN (-4450 3350);
DISPLAY INVISIBLE (-4450 3350);
FORCEPROP 1 LAST PART_NUMBER DFHST8FS479
J 0
(-5050 4600);
DISPLAY 0.468085 (-5050 4600);
PAINT SKYBLUE (-5050 4600);
DISPLAY INVISIBLE (-5050 4600);
FORCEADD GND..1
(-2900 5650);
FORCEPROP 3 LASTPIN (-2900 5700) SIG_NAME GND\g
J 0
(-2890 5710);
DISPLAY 0.659574 (-2890 5710);
PAINT MONO (-2890 5710);
DISPLAY INVISIBLE (-2890 5710);
FORCEPROP 2 LAST ROOM MEM_EFGH_DECOUPLING_CAPS
J 0
(-2875 5725);
DISPLAY 0.659574 (-2875 5725);
PAINT RED (-2875 5725);
DISPLAY INVISIBLE (-2875 5725);
FORCEPROP 1 LAST SIZE 1B
J 0
(-2825 5600);
DISPLAY 0.723404 (-2825 5600);
PAINT GREEN (-2825 5600);
DISPLAY INVISIBLE (-2825 5600);
FORCEPROP 2 LAST BOM_COST MEM
J 0
(-2875 5775);
DISPLAY 0.659574 (-2875 5775);
DISPLAY INVISIBLE (-2875 5775);
FORCEPROP 2 LAST CDS_LIB pure_quanta_power
J 0
(-2900 5650);
DISPLAY INVISIBLE (-2900 5650);
FORCEPROP 1 LAST HDL_POWER GND
J 0
(-2900 5800);
DISPLAY 0.723404 (-2900 5800);
PAINT GREEN (-2900 5800);
DISPLAY INVISIBLE (-2900 5800);
FORCEPROP 1 LAST PATH I238
J 0
(-2825 5650);
DISPLAY 0.872340 (-2825 5650);
PAINT AQUA (-2825 5650);
DISPLAY INVISIBLE (-2825 5650);
FORCEADD Q_CAP..1
R 2
(-2900 6000);
FORCEPROP 1 LAST LOCATION C159
J 2
(-2950 6100);
DISPLAY 0.489362 (-2950 6100);
PAINT SKYBLUE (-2950 6100);
FORCEPROP 0 LAST $SEC 1
J 0
(-2950 6150);
DISPLAY 0.680851 (-2950 6150);
PAINT MONO (-2950 6150);
DISPLAY INVISIBLE (-2950 6150);
FORCEPROP 0 LAST CDS_SEC 1
J 0
(-2950 6150);
DISPLAY 0.680851 (-2950 6150);
DISPLAY INVISIBLE (-2950 6150);
FORCEPROP 1 LASTPIN (-2900 6100) $PN 1
J 2
(-2910 6080);
DISPLAY 0.489362 (-2910 6080);
PAINT MONO (-2910 6080);
FORCEPROP 1 LASTPIN (-2900 5900) $PN 2
J 2
(-2910 5880);
DISPLAY 0.489362 (-2910 5880);
PAINT MONO (-2910 5880);
FORCEPROP 1 LAST MATERIAL X6S
J 2
(-2950 5900);
DISPLAY 0.489362 (-2950 5900);
PAINT SKYBLUE (-2950 5900);
FORCEPROP 1 LAST TOLERANCE 10%
J 2
(-2950 5950);
DISPLAY 0.489362 (-2950 5950);
PAINT SKYBLUE (-2950 5950);
FORCEPROP 1 LAST VALUE 10UF
J 2
(-2950 6050);
DISPLAY 0.489362 (-2950 6050);
PAINT SKYBLUE (-2950 6050);
FORCEPROP 1 LAST VOLTAGE 25V
J 2
(-2950 6000);
DISPLAY 0.489362 (-2950 6000);
PAINT SKYBLUE (-2950 6000);
FORCEPROP 1 LAST PACK_TYPE C0805
J 2
(-2950 5800);
DISPLAY 0.489362 (-2950 5800);
PAINT SKYBLUE (-2950 5800);
FORCEPROP 0 LAST BOM_COST MEM
J 2
(-2955 6145);
DISPLAY 0.595745 (-2955 6145);
PAINT MONO (-2955 6145);
DISPLAY INVISIBLE (-2955 6145);
FORCEPROP 2 LAST CDS_LIB pure_quanta
J 0
(-2900 6000);
DISPLAY INVISIBLE (-2900 6000);
FORCEPROP 2 LAST ROOM 
J 2
(-2955 6145);
DISPLAY 0.595745 (-2955 6145);
PAINT RED (-2955 6145);
DISPLAY INVISIBLE (-2955 6145);
FORCEPROP 1 LAST PATH I239
J 2
(-2950 6150);
DISPLAY 0.978723 (-2950 6150);
PAINT WHITE (-2950 6150);
DISPLAY INVISIBLE (-2950 6150);
FORCEPROP 1 LAST PART_NUMBER CH6104KEA00
J 2
(-2950 5850);
DISPLAY 0.489362 (-2950 5850);
PAINT SKYBLUE (-2950 5850);
DISPLAY INVISIBLE (-2950 5850);
FORCEADD TAP..1
R 2
(-7725 3200);
FORCEPROP 3 LASTPIN (-7675 3200) SIG_NAME M_H_CPU0_SB_CB<1>
J 0
(-7665 3210);
DISPLAY 0.659574 (-7665 3210);
PAINT MONO (-7665 3210);
DISPLAY INVISIBLE (-7665 3210);
FORCEPROP 1 LASTPIN (-7675 3200) BN 1
J 2
(-7663 3208);
DISPLAY 0.489362 (-7663 3208);
PAINT GREEN (-7663 3208);
FORCEPROP 2 LAST CDS_LIB mstr_standard
J 0
(-7725 3200);
DISPLAY 0.723404 (-7725 3200);
PAINT MONO (-7725 3200);
DISPLAY INVISIBLE (-7725 3200);
FORCEPROP 1 LAST BODY_TYPE PLUMBING
J 2
(-7725 3250);
DISPLAY 0.872340 (-7725 3250);
PAINT GREEN (-7725 3250);
DISPLAY INVISIBLE (-7725 3250);
FORCEPROP 1 LAST HDL_TAP TRUE
J 2
(-8050 3075);
DISPLAY 0.872340 (-8050 3075);
DISPLAY INVISIBLE (-8050 3075);
FORCEPROP 1 LAST PATH I24
J 2
(-7723 3200);
DISPLAY 0.872340 (-7723 3200);
PAINT GREEN (-7723 3200);
DISPLAY INVISIBLE (-7723 3200);
FORCEADD Q_CAP..1
R 2
(-2325 6000);
FORCEPROP 1 LAST LOCATION C161
J 2
(-2375 6100);
DISPLAY 0.489362 (-2375 6100);
PAINT SKYBLUE (-2375 6100);
FORCEPROP 0 LAST $SEC 1
J 0
(-2375 6150);
DISPLAY 0.680851 (-2375 6150);
PAINT MONO (-2375 6150);
DISPLAY INVISIBLE (-2375 6150);
FORCEPROP 0 LAST CDS_SEC 1
J 0
(-2375 6150);
DISPLAY 0.680851 (-2375 6150);
DISPLAY INVISIBLE (-2375 6150);
FORCEPROP 1 LASTPIN (-2325 6100) $PN 1
J 2
(-2335 6080);
DISPLAY 0.489362 (-2335 6080);
PAINT MONO (-2335 6080);
FORCEPROP 1 LASTPIN (-2325 5900) $PN 2
J 2
(-2335 5880);
DISPLAY 0.489362 (-2335 5880);
PAINT MONO (-2335 5880);
FORCEPROP 1 LAST VALUE 10UF
J 2
(-2375 6050);
DISPLAY 0.489362 (-2375 6050);
PAINT SKYBLUE (-2375 6050);
FORCEPROP 1 LAST VOLTAGE 25V
J 2
(-2375 6000);
DISPLAY 0.489362 (-2375 6000);
PAINT SKYBLUE (-2375 6000);
FORCEPROP 1 LAST MATERIAL X6S
J 2
(-2375 5900);
DISPLAY 0.489362 (-2375 5900);
PAINT SKYBLUE (-2375 5900);
FORCEPROP 1 LAST PACK_TYPE C0805
J 2
(-2375 5800);
DISPLAY 0.489362 (-2375 5800);
PAINT SKYBLUE (-2375 5800);
FORCEPROP 1 LAST TOLERANCE 10%
J 2
(-2375 5950);
DISPLAY 0.489362 (-2375 5950);
PAINT SKYBLUE (-2375 5950);
FORCEPROP 0 LAST BOM_COST MEM
J 2
(-2380 6145);
DISPLAY 0.595745 (-2380 6145);
PAINT MONO (-2380 6145);
DISPLAY INVISIBLE (-2380 6145);
FORCEPROP 2 LAST CDS_LIB pure_quanta
J 0
(-2325 6000);
DISPLAY INVISIBLE (-2325 6000);
FORCEPROP 2 LAST ROOM 
J 2
(-2380 6145);
DISPLAY 0.595745 (-2380 6145);
PAINT RED (-2380 6145);
DISPLAY INVISIBLE (-2380 6145);
FORCEPROP 1 LAST PATH I240
J 2
(-2375 6150);
DISPLAY 0.978723 (-2375 6150);
PAINT WHITE (-2375 6150);
DISPLAY INVISIBLE (-2375 6150);
FORCEPROP 1 LAST PART_NUMBER CH6104KEA00
J 2
(-2375 5850);
DISPLAY 0.489362 (-2375 5850);
PAINT SKYBLUE (-2375 5850);
DISPLAY INVISIBLE (-2375 5850);
FORCEADD UNIVERSAL_POWER..1
(-2900 6325);
FORCEPROP 3 LASTPIN (-2900 6275) SIG_NAME P12V_MEM_CPU0\g
J 0
(-2890 6285);
DISPLAY 0.659574 (-2890 6285);
PAINT MONO (-2890 6285);
DISPLAY INVISIBLE (-2890 6285);
FORCEPROP 1 LAST HDL_POWER P12V_MEM_CPU0
J 1
(-2925 6375);
DISPLAY 0.489362 (-2925 6375);
PAINT GREEN (-2925 6375);
FORCEPROP 2 LAST CDS_LIB pure_quanta_power
J 0
(-2900 6325);
DISPLAY INVISIBLE (-2900 6325);
FORCEPROP 2 LAST BOM_COST VR_SYSTEM
J 0
(-2900 6425);
DISPLAY 0.617021 (-2900 6425);
PAINT PURPLE (-2900 6425);
DISPLAY INVISIBLE (-2900 6425);
FORCEPROP 1 LAST PATH I241
J 0
(-2850 6350);
DISPLAY 0.872340 (-2850 6350);
PAINT AQUA (-2850 6350);
DISPLAY INVISIBLE (-2850 6350);
FORCEADD OFFPAGE..1
(-8425 2575);
FORCEPROP 2 LAST $XR5 97 
J 0
(-9127 2575);
DISPLAY 0.638298 (-9127 2575);
PAINT MONO (-9127 2575);
FORCEPROP 2 LAST $XR4 96 
J 0
(-9037 2575);
DISPLAY 0.638298 (-9037 2575);
PAINT MONO (-9037 2575);
FORCEPROP 2 LAST $XR3 95 
J 0
(-8947 2575);
DISPLAY 0.638298 (-8947 2575);
PAINT MONO (-8947 2575);
FORCEPROP 2 LAST $XR2 94 
J 0
(-8857 2575);
DISPLAY 0.638298 (-8857 2575);
PAINT MONO (-8857 2575);
FORCEPROP 2 LAST $XR1 92 
J 0
(-8767 2575);
DISPLAY 0.638298 (-8767 2575);
PAINT MONO (-8767 2575);
FORCEPROP 2 LAST $XR0 159 
J 0
(-8677 2575);
DISPLAY 0.638298 (-8677 2575);
PAINT MONO (-8677 2575);
FORCEPROP 2 LAST CDS_LIB mstr_standard
J 0
(-8425 2575);
DISPLAY 0.808511 (-8425 2575);
DISPLAY INVISIBLE (-8425 2575);
FORCEPROP 1 LAST OFFPAGE TRUE
J 0
(-8100 2450);
DISPLAY 0.872340 (-8100 2450);
PAINT GREEN (-8100 2450);
DISPLAY INVISIBLE (-8100 2450);
FORCEPROP 1 LAST COMMENT_BODY TRUE
J 0
(-8300 2475);
DISPLAY 0.872340 (-8300 2475);
PAINT GREEN (-8300 2475);
DISPLAY INVISIBLE (-8300 2475);
FORCEPROP 2 LAST PATH I242
J 0
(-8700 2625);
DISPLAY 0.680851 (-8700 2625);
DISPLAY INVISIBLE (-8700 2625);
FORCEADD Q_RES..1
(-7750 2575);
FORCEPROP 1 LAST LOCATION R1575
J 0
(-7800 2600);
DISPLAY 0.510638 (-7800 2600);
PAINT SKYBLUE (-7800 2600);
FORCEPROP 0 LAST $SEC 1
J 0
(-7800 2675);
DISPLAY 0.680851 (-7800 2675);
PAINT MONO (-7800 2675);
DISPLAY INVISIBLE (-7800 2675);
FORCEPROP 0 LAST CDS_SEC 1
J 0
(-7800 2675);
DISPLAY 0.680851 (-7800 2675);
DISPLAY INVISIBLE (-7800 2675);
FORCEPROP 1 LASTPIN (-7850 2575) $PN 1
J 0
(-7838 2587);
DISPLAY 0.787234 (-7838 2587);
PAINT MONO (-7838 2587);
FORCEPROP 1 LASTPIN (-7650 2575) $PN 2
J 0
(-7688 2587);
DISPLAY 0.787234 (-7688 2587);
PAINT MONO (-7688 2587);
FORCEPROP 1 LAST VALUE 49.9
J 2
(-7575 2625);
DISPLAY 0.510638 (-7575 2625);
PAINT SKYBLUE (-7575 2625);
FORCEPROP 1 LAST MATERIAL CHIP
J 0
(-7750 2425);
DISPLAY 0.978723 (-7750 2425);
DISPLAY INVISIBLE (-7750 2425);
FORCEPROP 1 LAST PACK_TYPE 0402LF
J 0
(-7500 2425);
DISPLAY 0.978723 (-7500 2425);
DISPLAY INVISIBLE (-7500 2425);
FORCEPROP 1 LAST WATTAGE 1/16W
J 2
(-7775 2425);
DISPLAY 0.978723 (-7775 2425);
DISPLAY INVISIBLE (-7775 2425);
FORCEPROP 1 LAST TOLERANCE 1%
J 0
(-7750 2475);
DISPLAY 0.978723 (-7750 2475);
DISPLAY INVISIBLE (-7750 2475);
FORCEPROP 2 LAST CDS_LIB pure_quanta
J 0
(-7750 2575);
DISPLAY INVISIBLE (-7750 2575);
FORCEPROP 1 LAST PATH I243
J 0
(-7800 2725);
DISPLAY 0.978723 (-7800 2725);
PAINT WHITE (-7800 2725);
DISPLAY INVISIBLE (-7800 2725);
FORCEPROP 1 LAST PART_NUMBER CS04992FB07
J 0
(-7800 2675);
DISPLAY 0.978723 (-7800 2675);
DISPLAY INVISIBLE (-7800 2675);
FORCEADD Q_RES..1
(-8150 2800);
FORCEPROP 1 LAST LOCATION R1681
J 0
(-8325 2800);
DISPLAY 0.510638 (-8325 2800);
FORCEPROP 0 LAST $SEC 1
J 0
(-8300 2850);
DISPLAY 0.680851 (-8300 2850);
PAINT MONO (-8300 2850);
DISPLAY INVISIBLE (-8300 2850);
FORCEPROP 0 LAST CDS_SEC 1
J 0
(-8300 2850);
DISPLAY 0.680851 (-8300 2850);
DISPLAY INVISIBLE (-8300 2850);
FORCEPROP 1 LASTPIN (-8250 2800) $PN 1
J 0
(-8238 2812);
DISPLAY 0.787234 (-8238 2812);
PAINT MONO (-8238 2812);
FORCEPROP 1 LASTPIN (-8050 2800) $PN 2
J 0
(-8088 2812);
DISPLAY 0.787234 (-8088 2812);
PAINT MONO (-8088 2812);
FORCEPROP 1 LAST MATERIAL CHIP
J 0
(-8250 2775);
DISPLAY 0.404255 (-8250 2775);
FORCEPROP 1 LAST PACK_TYPE 0402LF
J 0
(-8100 2775);
DISPLAY 0.404255 (-8100 2775);
FORCEPROP 1 LAST VALUE 10
J 2
(-8000 2800);
DISPLAY 0.404255 (-8000 2800);
FORCEPROP 2 LAST CDS_LIB pure_quanta
J 0
(-8150 2800);
DISPLAY INVISIBLE (-8150 2800);
FORCEPROP 1 LAST WATTAGE 1/16W
J 2
(-8175 2650);
DISPLAY 0.978723 (-8175 2650);
DISPLAY INVISIBLE (-8175 2650);
FORCEPROP 1 LAST TOLERANCE 1%
J 0
(-8150 2700);
DISPLAY 0.978723 (-8150 2700);
DISPLAY INVISIBLE (-8150 2700);
FORCEPROP 1 LAST PATH I244
J 0
(-8200 2950);
DISPLAY 0.978723 (-8200 2950);
PAINT WHITE (-8200 2950);
DISPLAY INVISIBLE (-8200 2950);
FORCEPROP 1 LAST PART_NUMBER CS01002FB07
J 0
(-8200 2900);
DISPLAY 0.978723 (-8200 2900);
DISPLAY INVISIBLE (-8200 2900);
FORCEADD OFFPAGE..6
(-8825 2725);
FORCEPROP 2 LAST $XR5 159 
J 0
(-9314 2689);
DISPLAY 0.638298 (-9314 2689);
PAINT MONO (-9314 2689);
FORCEPROP 2 LAST $XR4 97 
J 0
(-9194 2689);
DISPLAY 0.638298 (-9194 2689);
PAINT MONO (-9194 2689);
FORCEPROP 2 LAST $XR3 96 
J 0
(-9104 2689);
DISPLAY 0.638298 (-9104 2689);
PAINT MONO (-9104 2689);
FORCEPROP 2 LAST $XR2 95 
J 0
(-9284 2725);
DISPLAY 0.638298 (-9284 2725);
PAINT MONO (-9284 2725);
FORCEPROP 2 LAST $XR1 94 
J 0
(-9194 2725);
DISPLAY 0.638298 (-9194 2725);
PAINT MONO (-9194 2725);
FORCEPROP 2 LAST $XR0 92 
J 0
(-9104 2725);
DISPLAY 0.638298 (-9104 2725);
PAINT MONO (-9104 2725);
FORCEPROP 2 LAST CDS_LIB mstr_standard
J 0
(-8825 2725);
DISPLAY 0.808511 (-8825 2725);
DISPLAY INVISIBLE (-8825 2725);
FORCEPROP 1 LAST OFFPAGE TRUE
J 0
(-8500 2600);
DISPLAY 0.872340 (-8500 2600);
PAINT GREEN (-8500 2600);
DISPLAY INVISIBLE (-8500 2600);
FORCEPROP 1 LAST COMMENT_BODY TRUE
J 0
(-8725 2650);
DISPLAY 0.872340 (-8725 2650);
PAINT GREEN (-8725 2650);
DISPLAY INVISIBLE (-8725 2650);
FORCEPROP 2 LAST PATH I245
J 0
(-9050 2775);
DISPLAY 0.680851 (-9050 2775);
DISPLAY INVISIBLE (-9050 2775);
FORCEADD TAP..1
R 2
(-7725 3250);
FORCEPROP 3 LASTPIN (-7675 3250) SIG_NAME M_H_CPU0_SB_CB<2>
J 0
(-7665 3260);
DISPLAY 0.659574 (-7665 3260);
PAINT MONO (-7665 3260);
DISPLAY INVISIBLE (-7665 3260);
FORCEPROP 1 LASTPIN (-7675 3250) BN 2
J 2
(-7663 3258);
DISPLAY 0.489362 (-7663 3258);
PAINT GREEN (-7663 3258);
FORCEPROP 2 LAST CDS_LIB mstr_standard
J 0
(-7725 3250);
DISPLAY 0.723404 (-7725 3250);
PAINT MONO (-7725 3250);
DISPLAY INVISIBLE (-7725 3250);
FORCEPROP 1 LAST BODY_TYPE PLUMBING
J 2
(-7725 3300);
DISPLAY 0.872340 (-7725 3300);
PAINT GREEN (-7725 3300);
DISPLAY INVISIBLE (-7725 3300);
FORCEPROP 1 LAST HDL_TAP TRUE
J 2
(-8050 3125);
DISPLAY 0.872340 (-8050 3125);
DISPLAY INVISIBLE (-8050 3125);
FORCEPROP 1 LAST PATH I25
J 2
(-7723 3250);
DISPLAY 0.872340 (-7723 3250);
PAINT GREEN (-7723 3250);
DISPLAY INVISIBLE (-7723 3250);
FORCEADD TAP..1
R 2
(-7725 3300);
FORCEPROP 3 LASTPIN (-7675 3300) SIG_NAME M_H_CPU0_SB_CB<3>
J 0
(-7665 3310);
DISPLAY 0.659574 (-7665 3310);
PAINT MONO (-7665 3310);
DISPLAY INVISIBLE (-7665 3310);
FORCEPROP 1 LASTPIN (-7675 3300) BN 3
J 2
(-7663 3308);
DISPLAY 0.489362 (-7663 3308);
PAINT GREEN (-7663 3308);
FORCEPROP 2 LAST CDS_LIB mstr_standard
J 0
(-7725 3300);
DISPLAY 0.723404 (-7725 3300);
PAINT MONO (-7725 3300);
DISPLAY INVISIBLE (-7725 3300);
FORCEPROP 1 LAST BODY_TYPE PLUMBING
J 2
(-7725 3350);
DISPLAY 0.872340 (-7725 3350);
PAINT GREEN (-7725 3350);
DISPLAY INVISIBLE (-7725 3350);
FORCEPROP 1 LAST HDL_TAP TRUE
J 2
(-8050 3175);
DISPLAY 0.872340 (-8050 3175);
DISPLAY INVISIBLE (-8050 3175);
FORCEPROP 1 LAST PATH I26
J 2
(-7723 3300);
DISPLAY 0.872340 (-7723 3300);
PAINT GREEN (-7723 3300);
DISPLAY INVISIBLE (-7723 3300);
FORCEADD TAP..1
R 2
(-7725 3350);
FORCEPROP 3 LASTPIN (-7675 3350) SIG_NAME M_H_CPU0_SB_CB<4>
J 0
(-7665 3360);
DISPLAY 0.659574 (-7665 3360);
PAINT MONO (-7665 3360);
DISPLAY INVISIBLE (-7665 3360);
FORCEPROP 1 LASTPIN (-7675 3350) BN 4
J 2
(-7663 3358);
DISPLAY 0.489362 (-7663 3358);
PAINT GREEN (-7663 3358);
FORCEPROP 2 LAST CDS_LIB mstr_standard
J 0
(-7725 3350);
DISPLAY 0.723404 (-7725 3350);
PAINT MONO (-7725 3350);
DISPLAY INVISIBLE (-7725 3350);
FORCEPROP 1 LAST BODY_TYPE PLUMBING
J 2
(-7725 3400);
DISPLAY 0.872340 (-7725 3400);
PAINT GREEN (-7725 3400);
DISPLAY INVISIBLE (-7725 3400);
FORCEPROP 1 LAST HDL_TAP TRUE
J 2
(-8050 3225);
DISPLAY 0.872340 (-8050 3225);
DISPLAY INVISIBLE (-8050 3225);
FORCEPROP 1 LAST PATH I27
J 2
(-7723 3350);
DISPLAY 0.872340 (-7723 3350);
PAINT GREEN (-7723 3350);
DISPLAY INVISIBLE (-7723 3350);
FORCEADD TAP..1
R 2
(-7725 3450);
FORCEPROP 3 LASTPIN (-7675 3450) SIG_NAME M_H_CPU0_SB_CB<6>
J 0
(-7665 3460);
DISPLAY 0.659574 (-7665 3460);
PAINT MONO (-7665 3460);
DISPLAY INVISIBLE (-7665 3460);
FORCEPROP 1 LASTPIN (-7675 3450) BN 6
J 2
(-7663 3458);
DISPLAY 0.489362 (-7663 3458);
PAINT GREEN (-7663 3458);
FORCEPROP 2 LAST CDS_LIB mstr_standard
J 0
(-7725 3450);
DISPLAY 0.723404 (-7725 3450);
PAINT MONO (-7725 3450);
DISPLAY INVISIBLE (-7725 3450);
FORCEPROP 1 LAST BODY_TYPE PLUMBING
J 2
(-7725 3500);
DISPLAY 0.872340 (-7725 3500);
PAINT GREEN (-7725 3500);
DISPLAY INVISIBLE (-7725 3500);
FORCEPROP 1 LAST HDL_TAP TRUE
J 2
(-8050 3325);
DISPLAY 0.872340 (-8050 3325);
DISPLAY INVISIBLE (-8050 3325);
FORCEPROP 1 LAST PATH I28
J 2
(-7723 3450);
DISPLAY 0.872340 (-7723 3450);
PAINT GREEN (-7723 3450);
DISPLAY INVISIBLE (-7723 3450);
FORCEADD TAP..1
R 2
(-7725 3400);
FORCEPROP 3 LASTPIN (-7675 3400) SIG_NAME M_H_CPU0_SB_CB<5>
J 0
(-7665 3410);
DISPLAY 0.659574 (-7665 3410);
PAINT MONO (-7665 3410);
DISPLAY INVISIBLE (-7665 3410);
FORCEPROP 1 LASTPIN (-7675 3400) BN 5
J 2
(-7663 3408);
DISPLAY 0.489362 (-7663 3408);
PAINT GREEN (-7663 3408);
FORCEPROP 2 LAST CDS_LIB mstr_standard
J 0
(-7725 3400);
DISPLAY 0.723404 (-7725 3400);
PAINT MONO (-7725 3400);
DISPLAY INVISIBLE (-7725 3400);
FORCEPROP 1 LAST BODY_TYPE PLUMBING
J 2
(-7725 3450);
DISPLAY 0.872340 (-7725 3450);
PAINT GREEN (-7725 3450);
DISPLAY INVISIBLE (-7725 3450);
FORCEPROP 1 LAST HDL_TAP TRUE
J 2
(-8050 3275);
DISPLAY 0.872340 (-8050 3275);
DISPLAY INVISIBLE (-8050 3275);
FORCEPROP 1 LAST PATH I29
J 2
(-7723 3400);
DISPLAY 0.872340 (-7723 3400);
PAINT GREEN (-7723 3400);
DISPLAY INVISIBLE (-7723 3400);
FORCEADD TAP..1
R 2
(-7725 3500);
FORCEPROP 3 LASTPIN (-7675 3500) SIG_NAME M_H_CPU0_SB_CB<7>
J 0
(-7665 3510);
DISPLAY 0.659574 (-7665 3510);
PAINT MONO (-7665 3510);
DISPLAY INVISIBLE (-7665 3510);
FORCEPROP 1 LASTPIN (-7675 3500) BN 7
J 2
(-7663 3508);
DISPLAY 0.489362 (-7663 3508);
PAINT GREEN (-7663 3508);
FORCEPROP 2 LAST CDS_LIB mstr_standard
J 0
(-7725 3500);
DISPLAY 0.723404 (-7725 3500);
PAINT MONO (-7725 3500);
DISPLAY INVISIBLE (-7725 3500);
FORCEPROP 1 LAST BODY_TYPE PLUMBING
J 2
(-7725 3550);
DISPLAY 0.872340 (-7725 3550);
PAINT GREEN (-7725 3550);
DISPLAY INVISIBLE (-7725 3550);
FORCEPROP 1 LAST HDL_TAP TRUE
J 2
(-8050 3375);
DISPLAY 0.872340 (-8050 3375);
DISPLAY INVISIBLE (-8050 3375);
FORCEPROP 1 LAST PATH I30
J 2
(-7723 3500);
DISPLAY 0.872340 (-7723 3500);
PAINT GREEN (-7723 3500);
DISPLAY INVISIBLE (-7723 3500);
FORCEADD TAP..1
R 2
(-7725 3600);
FORCEPROP 3 LASTPIN (-7675 3600) SIG_NAME M_H_CPU0_SA_CB<0>
J 0
(-7665 3610);
DISPLAY 0.659574 (-7665 3610);
PAINT MONO (-7665 3610);
DISPLAY INVISIBLE (-7665 3610);
FORCEPROP 1 LASTPIN (-7675 3600) BN 0
J 2
(-7663 3608);
DISPLAY 0.489362 (-7663 3608);
PAINT GREEN (-7663 3608);
FORCEPROP 2 LAST CDS_LIB mstr_standard
J 0
(-7725 3600);
DISPLAY 0.723404 (-7725 3600);
PAINT MONO (-7725 3600);
DISPLAY INVISIBLE (-7725 3600);
FORCEPROP 1 LAST BODY_TYPE PLUMBING
J 2
(-7725 3650);
DISPLAY 0.872340 (-7725 3650);
PAINT GREEN (-7725 3650);
DISPLAY INVISIBLE (-7725 3650);
FORCEPROP 1 LAST HDL_TAP TRUE
J 2
(-8050 3475);
DISPLAY 0.872340 (-8050 3475);
DISPLAY INVISIBLE (-8050 3475);
FORCEPROP 1 LAST PATH I31
J 2
(-7723 3600);
DISPLAY 0.872340 (-7723 3600);
PAINT GREEN (-7723 3600);
DISPLAY INVISIBLE (-7723 3600);
FORCEADD TAP..1
R 2
(-7725 3650);
FORCEPROP 3 LASTPIN (-7675 3650) SIG_NAME M_H_CPU0_SA_CB<1>
J 0
(-7665 3660);
DISPLAY 0.659574 (-7665 3660);
PAINT MONO (-7665 3660);
DISPLAY INVISIBLE (-7665 3660);
FORCEPROP 1 LASTPIN (-7675 3650) BN 1
J 2
(-7663 3658);
DISPLAY 0.489362 (-7663 3658);
PAINT GREEN (-7663 3658);
FORCEPROP 2 LAST CDS_LIB mstr_standard
J 0
(-7725 3650);
DISPLAY 0.723404 (-7725 3650);
PAINT MONO (-7725 3650);
DISPLAY INVISIBLE (-7725 3650);
FORCEPROP 1 LAST BODY_TYPE PLUMBING
J 2
(-7725 3700);
DISPLAY 0.872340 (-7725 3700);
PAINT GREEN (-7725 3700);
DISPLAY INVISIBLE (-7725 3700);
FORCEPROP 1 LAST HDL_TAP TRUE
J 2
(-8050 3525);
DISPLAY 0.872340 (-8050 3525);
DISPLAY INVISIBLE (-8050 3525);
FORCEPROP 1 LAST PATH I32
J 2
(-7723 3650);
DISPLAY 0.872340 (-7723 3650);
PAINT GREEN (-7723 3650);
DISPLAY INVISIBLE (-7723 3650);
FORCEADD TAP..1
R 2
(-7725 3700);
FORCEPROP 3 LASTPIN (-7675 3700) SIG_NAME M_H_CPU0_SA_CB<2>
J 0
(-7665 3710);
DISPLAY 0.659574 (-7665 3710);
PAINT MONO (-7665 3710);
DISPLAY INVISIBLE (-7665 3710);
FORCEPROP 1 LASTPIN (-7675 3700) BN 2
J 2
(-7663 3708);
DISPLAY 0.489362 (-7663 3708);
PAINT GREEN (-7663 3708);
FORCEPROP 2 LAST CDS_LIB mstr_standard
J 0
(-7725 3700);
DISPLAY 0.723404 (-7725 3700);
PAINT MONO (-7725 3700);
DISPLAY INVISIBLE (-7725 3700);
FORCEPROP 1 LAST BODY_TYPE PLUMBING
J 2
(-7725 3750);
DISPLAY 0.872340 (-7725 3750);
PAINT GREEN (-7725 3750);
DISPLAY INVISIBLE (-7725 3750);
FORCEPROP 1 LAST HDL_TAP TRUE
J 2
(-8050 3575);
DISPLAY 0.872340 (-8050 3575);
DISPLAY INVISIBLE (-8050 3575);
FORCEPROP 1 LAST PATH I33
J 2
(-7723 3700);
DISPLAY 0.872340 (-7723 3700);
PAINT GREEN (-7723 3700);
DISPLAY INVISIBLE (-7723 3700);
FORCEADD TAP..1
R 2
(-7725 3750);
FORCEPROP 3 LASTPIN (-7675 3750) SIG_NAME M_H_CPU0_SA_CB<3>
J 0
(-7665 3760);
DISPLAY 0.659574 (-7665 3760);
PAINT MONO (-7665 3760);
DISPLAY INVISIBLE (-7665 3760);
FORCEPROP 1 LASTPIN (-7675 3750) BN 3
J 2
(-7663 3758);
DISPLAY 0.489362 (-7663 3758);
PAINT GREEN (-7663 3758);
FORCEPROP 2 LAST CDS_LIB mstr_standard
J 0
(-7725 3750);
DISPLAY 0.723404 (-7725 3750);
PAINT MONO (-7725 3750);
DISPLAY INVISIBLE (-7725 3750);
FORCEPROP 1 LAST BODY_TYPE PLUMBING
J 2
(-7725 3800);
DISPLAY 0.872340 (-7725 3800);
PAINT GREEN (-7725 3800);
DISPLAY INVISIBLE (-7725 3800);
FORCEPROP 1 LAST HDL_TAP TRUE
J 2
(-8050 3625);
DISPLAY 0.872340 (-8050 3625);
DISPLAY INVISIBLE (-8050 3625);
FORCEPROP 1 LAST PATH I34
J 2
(-7723 3750);
DISPLAY 0.872340 (-7723 3750);
PAINT GREEN (-7723 3750);
DISPLAY INVISIBLE (-7723 3750);
FORCEADD TAP..1
(-6025 2150);
FORCEPROP 3 LASTPIN (-6075 2150) SIG_NAME M_H_CPU0_SB_DQ<0>
J 0
(-6065 2160);
DISPLAY 0.659574 (-6065 2160);
PAINT MONO (-6065 2160);
DISPLAY INVISIBLE (-6065 2160);
FORCEPROP 1 LASTPIN (-6075 2150) BN 0
J 0
(-6087 2158);
DISPLAY 0.489362 (-6087 2158);
PAINT GREEN (-6087 2158);
FORCEPROP 2 LAST CDS_LIB mstr_standard
J 0
(-6025 2150);
DISPLAY 0.723404 (-6025 2150);
PAINT MONO (-6025 2150);
DISPLAY INVISIBLE (-6025 2150);
FORCEPROP 1 LAST BODY_TYPE PLUMBING
J 0
(-6025 2200);
DISPLAY 0.872340 (-6025 2200);
PAINT GREEN (-6025 2200);
DISPLAY INVISIBLE (-6025 2200);
FORCEPROP 1 LAST HDL_TAP TRUE
J 0
(-5700 2025);
DISPLAY 0.872340 (-5700 2025);
DISPLAY INVISIBLE (-5700 2025);
FORCEPROP 1 LAST PATH I35
J 0
(-6027 2150);
DISPLAY 0.872340 (-6027 2150);
PAINT GREEN (-6027 2150);
DISPLAY INVISIBLE (-6027 2150);
FORCEADD TAP..1
(-6025 2200);
FORCEPROP 3 LASTPIN (-6075 2200) SIG_NAME M_H_CPU0_SB_DQ<1>
J 0
(-6065 2210);
DISPLAY 0.659574 (-6065 2210);
PAINT MONO (-6065 2210);
DISPLAY INVISIBLE (-6065 2210);
FORCEPROP 1 LASTPIN (-6075 2200) BN 1
J 0
(-6087 2208);
DISPLAY 0.489362 (-6087 2208);
PAINT GREEN (-6087 2208);
FORCEPROP 2 LAST CDS_LIB mstr_standard
J 0
(-6025 2200);
DISPLAY 0.723404 (-6025 2200);
PAINT MONO (-6025 2200);
DISPLAY INVISIBLE (-6025 2200);
FORCEPROP 1 LAST BODY_TYPE PLUMBING
J 0
(-6025 2250);
DISPLAY 0.872340 (-6025 2250);
PAINT GREEN (-6025 2250);
DISPLAY INVISIBLE (-6025 2250);
FORCEPROP 1 LAST HDL_TAP TRUE
J 0
(-5700 2075);
DISPLAY 0.872340 (-5700 2075);
DISPLAY INVISIBLE (-5700 2075);
FORCEPROP 1 LAST PATH I36
J 0
(-6027 2200);
DISPLAY 0.872340 (-6027 2200);
PAINT GREEN (-6027 2200);
DISPLAY INVISIBLE (-6027 2200);
FORCEADD TAP..1
(-6025 2250);
FORCEPROP 3 LASTPIN (-6075 2250) SIG_NAME M_H_CPU0_SB_DQ<2>
J 0
(-6065 2260);
DISPLAY 0.659574 (-6065 2260);
PAINT MONO (-6065 2260);
DISPLAY INVISIBLE (-6065 2260);
FORCEPROP 1 LASTPIN (-6075 2250) BN 2
J 0
(-6087 2258);
DISPLAY 0.489362 (-6087 2258);
PAINT GREEN (-6087 2258);
FORCEPROP 2 LAST CDS_LIB mstr_standard
J 0
(-6025 2250);
DISPLAY 0.723404 (-6025 2250);
PAINT MONO (-6025 2250);
DISPLAY INVISIBLE (-6025 2250);
FORCEPROP 1 LAST BODY_TYPE PLUMBING
J 0
(-6025 2300);
DISPLAY 0.872340 (-6025 2300);
PAINT GREEN (-6025 2300);
DISPLAY INVISIBLE (-6025 2300);
FORCEPROP 1 LAST HDL_TAP TRUE
J 0
(-5700 2125);
DISPLAY 0.872340 (-5700 2125);
DISPLAY INVISIBLE (-5700 2125);
FORCEPROP 1 LAST PATH I37
J 0
(-6027 2250);
DISPLAY 0.872340 (-6027 2250);
PAINT GREEN (-6027 2250);
DISPLAY INVISIBLE (-6027 2250);
FORCEADD TAP..1
(-6025 2300);
FORCEPROP 3 LASTPIN (-6075 2300) SIG_NAME M_H_CPU0_SB_DQ<3>
J 0
(-6065 2310);
DISPLAY 0.659574 (-6065 2310);
PAINT MONO (-6065 2310);
DISPLAY INVISIBLE (-6065 2310);
FORCEPROP 1 LASTPIN (-6075 2300) BN 3
J 0
(-6087 2308);
DISPLAY 0.489362 (-6087 2308);
PAINT GREEN (-6087 2308);
FORCEPROP 2 LAST CDS_LIB mstr_standard
J 0
(-6025 2300);
DISPLAY 0.723404 (-6025 2300);
PAINT MONO (-6025 2300);
DISPLAY INVISIBLE (-6025 2300);
FORCEPROP 1 LAST BODY_TYPE PLUMBING
J 0
(-6025 2350);
DISPLAY 0.872340 (-6025 2350);
PAINT GREEN (-6025 2350);
DISPLAY INVISIBLE (-6025 2350);
FORCEPROP 1 LAST HDL_TAP TRUE
J 0
(-5700 2175);
DISPLAY 0.872340 (-5700 2175);
DISPLAY INVISIBLE (-5700 2175);
FORCEPROP 1 LAST PATH I38
J 0
(-6027 2300);
DISPLAY 0.872340 (-6027 2300);
PAINT GREEN (-6027 2300);
DISPLAY INVISIBLE (-6027 2300);
FORCEADD TAP..1
(-6025 2350);
FORCEPROP 3 LASTPIN (-6075 2350) SIG_NAME M_H_CPU0_SB_DQ<4>
J 0
(-6065 2360);
DISPLAY 0.659574 (-6065 2360);
PAINT MONO (-6065 2360);
DISPLAY INVISIBLE (-6065 2360);
FORCEPROP 1 LASTPIN (-6075 2350) BN 4
J 0
(-6087 2358);
DISPLAY 0.489362 (-6087 2358);
PAINT GREEN (-6087 2358);
FORCEPROP 2 LAST CDS_LIB mstr_standard
J 0
(-6025 2350);
DISPLAY 0.723404 (-6025 2350);
PAINT MONO (-6025 2350);
DISPLAY INVISIBLE (-6025 2350);
FORCEPROP 1 LAST BODY_TYPE PLUMBING
J 0
(-6025 2400);
DISPLAY 0.872340 (-6025 2400);
PAINT GREEN (-6025 2400);
DISPLAY INVISIBLE (-6025 2400);
FORCEPROP 1 LAST HDL_TAP TRUE
J 0
(-5700 2225);
DISPLAY 0.872340 (-5700 2225);
DISPLAY INVISIBLE (-5700 2225);
FORCEPROP 1 LAST PATH I39
J 0
(-6027 2350);
DISPLAY 0.872340 (-6027 2350);
PAINT GREEN (-6027 2350);
DISPLAY INVISIBLE (-6027 2350);
FORCEADD TAP..1
(-6025 2400);
FORCEPROP 3 LASTPIN (-6075 2400) SIG_NAME M_H_CPU0_SB_DQ<5>
J 0
(-6065 2410);
DISPLAY 0.659574 (-6065 2410);
PAINT MONO (-6065 2410);
DISPLAY INVISIBLE (-6065 2410);
FORCEPROP 1 LASTPIN (-6075 2400) BN 5
J 0
(-6087 2408);
DISPLAY 0.489362 (-6087 2408);
PAINT GREEN (-6087 2408);
FORCEPROP 2 LAST CDS_LIB mstr_standard
J 0
(-6025 2400);
DISPLAY 0.723404 (-6025 2400);
PAINT MONO (-6025 2400);
DISPLAY INVISIBLE (-6025 2400);
FORCEPROP 1 LAST BODY_TYPE PLUMBING
J 0
(-6025 2450);
DISPLAY 0.872340 (-6025 2450);
PAINT GREEN (-6025 2450);
DISPLAY INVISIBLE (-6025 2450);
FORCEPROP 1 LAST HDL_TAP TRUE
J 0
(-5700 2275);
DISPLAY 0.872340 (-5700 2275);
DISPLAY INVISIBLE (-5700 2275);
FORCEPROP 1 LAST PATH I40
J 0
(-6027 2400);
DISPLAY 0.872340 (-6027 2400);
PAINT GREEN (-6027 2400);
DISPLAY INVISIBLE (-6027 2400);
FORCEADD TAP..1
(-6025 2450);
FORCEPROP 3 LASTPIN (-6075 2450) SIG_NAME M_H_CPU0_SB_DQ<6>
J 0
(-6065 2460);
DISPLAY 0.659574 (-6065 2460);
PAINT MONO (-6065 2460);
DISPLAY INVISIBLE (-6065 2460);
FORCEPROP 1 LASTPIN (-6075 2450) BN 6
J 0
(-6087 2458);
DISPLAY 0.489362 (-6087 2458);
PAINT GREEN (-6087 2458);
FORCEPROP 2 LAST CDS_LIB mstr_standard
J 0
(-6025 2450);
DISPLAY 0.723404 (-6025 2450);
PAINT MONO (-6025 2450);
DISPLAY INVISIBLE (-6025 2450);
FORCEPROP 1 LAST BODY_TYPE PLUMBING
J 0
(-6025 2500);
DISPLAY 0.872340 (-6025 2500);
PAINT GREEN (-6025 2500);
DISPLAY INVISIBLE (-6025 2500);
FORCEPROP 1 LAST HDL_TAP TRUE
J 0
(-5700 2325);
DISPLAY 0.872340 (-5700 2325);
DISPLAY INVISIBLE (-5700 2325);
FORCEPROP 1 LAST PATH I41
J 0
(-6027 2450);
DISPLAY 0.872340 (-6027 2450);
PAINT GREEN (-6027 2450);
DISPLAY INVISIBLE (-6027 2450);
FORCEADD TAP..1
(-6025 2500);
FORCEPROP 3 LASTPIN (-6075 2500) SIG_NAME M_H_CPU0_SB_DQ<7>
J 0
(-6065 2510);
DISPLAY 0.659574 (-6065 2510);
PAINT MONO (-6065 2510);
DISPLAY INVISIBLE (-6065 2510);
FORCEPROP 1 LASTPIN (-6075 2500) BN 7
J 0
(-6087 2508);
DISPLAY 0.489362 (-6087 2508);
PAINT GREEN (-6087 2508);
FORCEPROP 2 LAST CDS_LIB mstr_standard
J 0
(-6025 2500);
DISPLAY 0.723404 (-6025 2500);
PAINT MONO (-6025 2500);
DISPLAY INVISIBLE (-6025 2500);
FORCEPROP 1 LAST BODY_TYPE PLUMBING
J 0
(-6025 2550);
DISPLAY 0.872340 (-6025 2550);
PAINT GREEN (-6025 2550);
DISPLAY INVISIBLE (-6025 2550);
FORCEPROP 1 LAST HDL_TAP TRUE
J 0
(-5700 2375);
DISPLAY 0.872340 (-5700 2375);
DISPLAY INVISIBLE (-5700 2375);
FORCEPROP 1 LAST PATH I42
J 0
(-6027 2500);
DISPLAY 0.872340 (-6027 2500);
PAINT GREEN (-6027 2500);
DISPLAY INVISIBLE (-6027 2500);
FORCEADD TAP..1
(-6025 2550);
FORCEPROP 3 LASTPIN (-6075 2550) SIG_NAME M_H_CPU0_SB_DQ<8>
J 0
(-6065 2560);
DISPLAY 0.659574 (-6065 2560);
PAINT MONO (-6065 2560);
DISPLAY INVISIBLE (-6065 2560);
FORCEPROP 1 LASTPIN (-6075 2550) BN 8
J 0
(-6087 2558);
DISPLAY 0.489362 (-6087 2558);
PAINT GREEN (-6087 2558);
FORCEPROP 2 LAST CDS_LIB mstr_standard
J 0
(-6025 2550);
DISPLAY 0.723404 (-6025 2550);
PAINT MONO (-6025 2550);
DISPLAY INVISIBLE (-6025 2550);
FORCEPROP 1 LAST BODY_TYPE PLUMBING
J 0
(-6025 2600);
DISPLAY 0.872340 (-6025 2600);
PAINT GREEN (-6025 2600);
DISPLAY INVISIBLE (-6025 2600);
FORCEPROP 1 LAST HDL_TAP TRUE
J 0
(-5700 2425);
DISPLAY 0.872340 (-5700 2425);
DISPLAY INVISIBLE (-5700 2425);
FORCEPROP 1 LAST PATH I43
J 0
(-6027 2550);
DISPLAY 0.872340 (-6027 2550);
PAINT GREEN (-6027 2550);
DISPLAY INVISIBLE (-6027 2550);
FORCEADD TAP..1
(-6025 2600);
FORCEPROP 3 LASTPIN (-6075 2600) SIG_NAME M_H_CPU0_SB_DQ<9>
J 0
(-6065 2610);
DISPLAY 0.659574 (-6065 2610);
PAINT MONO (-6065 2610);
DISPLAY INVISIBLE (-6065 2610);
FORCEPROP 1 LASTPIN (-6075 2600) BN 9
J 0
(-6087 2608);
DISPLAY 0.489362 (-6087 2608);
PAINT GREEN (-6087 2608);
FORCEPROP 2 LAST CDS_LIB mstr_standard
J 0
(-6025 2600);
DISPLAY 0.723404 (-6025 2600);
PAINT MONO (-6025 2600);
DISPLAY INVISIBLE (-6025 2600);
FORCEPROP 1 LAST BODY_TYPE PLUMBING
J 0
(-6025 2650);
DISPLAY 0.872340 (-6025 2650);
PAINT GREEN (-6025 2650);
DISPLAY INVISIBLE (-6025 2650);
FORCEPROP 1 LAST HDL_TAP TRUE
J 0
(-5700 2475);
DISPLAY 0.872340 (-5700 2475);
DISPLAY INVISIBLE (-5700 2475);
FORCEPROP 1 LAST PATH I44
J 0
(-6027 2600);
DISPLAY 0.872340 (-6027 2600);
PAINT GREEN (-6027 2600);
DISPLAY INVISIBLE (-6027 2600);
FORCEADD TAP..1
(-6025 2650);
FORCEPROP 3 LASTPIN (-6075 2650) SIG_NAME M_H_CPU0_SB_DQ<10>
J 0
(-6065 2660);
DISPLAY 0.659574 (-6065 2660);
PAINT MONO (-6065 2660);
DISPLAY INVISIBLE (-6065 2660);
FORCEPROP 1 LASTPIN (-6075 2650) BN 10
J 0
(-6087 2658);
DISPLAY 0.489362 (-6087 2658);
PAINT GREEN (-6087 2658);
FORCEPROP 2 LAST CDS_LIB mstr_standard
J 0
(-6025 2650);
DISPLAY 0.723404 (-6025 2650);
PAINT MONO (-6025 2650);
DISPLAY INVISIBLE (-6025 2650);
FORCEPROP 1 LAST BODY_TYPE PLUMBING
J 0
(-6025 2700);
DISPLAY 0.872340 (-6025 2700);
PAINT GREEN (-6025 2700);
DISPLAY INVISIBLE (-6025 2700);
FORCEPROP 1 LAST HDL_TAP TRUE
J 0
(-5700 2525);
DISPLAY 0.872340 (-5700 2525);
DISPLAY INVISIBLE (-5700 2525);
FORCEPROP 1 LAST PATH I45
J 0
(-6027 2650);
DISPLAY 0.872340 (-6027 2650);
PAINT GREEN (-6027 2650);
DISPLAY INVISIBLE (-6027 2650);
FORCEADD TAP..1
(-6025 2700);
FORCEPROP 3 LASTPIN (-6075 2700) SIG_NAME M_H_CPU0_SB_DQ<11>
J 0
(-6065 2710);
DISPLAY 0.659574 (-6065 2710);
PAINT MONO (-6065 2710);
DISPLAY INVISIBLE (-6065 2710);
FORCEPROP 1 LASTPIN (-6075 2700) BN 11
J 0
(-6087 2708);
DISPLAY 0.489362 (-6087 2708);
PAINT GREEN (-6087 2708);
FORCEPROP 2 LAST CDS_LIB mstr_standard
J 0
(-6025 2700);
DISPLAY 0.723404 (-6025 2700);
PAINT MONO (-6025 2700);
DISPLAY INVISIBLE (-6025 2700);
FORCEPROP 1 LAST BODY_TYPE PLUMBING
J 0
(-6025 2750);
DISPLAY 0.872340 (-6025 2750);
PAINT GREEN (-6025 2750);
DISPLAY INVISIBLE (-6025 2750);
FORCEPROP 1 LAST HDL_TAP TRUE
J 0
(-5700 2575);
DISPLAY 0.872340 (-5700 2575);
DISPLAY INVISIBLE (-5700 2575);
FORCEPROP 1 LAST PATH I46
J 0
(-6027 2700);
DISPLAY 0.872340 (-6027 2700);
PAINT GREEN (-6027 2700);
DISPLAY INVISIBLE (-6027 2700);
FORCEADD TAP..1
(-6025 2750);
FORCEPROP 3 LASTPIN (-6075 2750) SIG_NAME M_H_CPU0_SB_DQ<12>
J 0
(-6065 2760);
DISPLAY 0.659574 (-6065 2760);
PAINT MONO (-6065 2760);
DISPLAY INVISIBLE (-6065 2760);
FORCEPROP 1 LASTPIN (-6075 2750) BN 12
J 0
(-6087 2758);
DISPLAY 0.489362 (-6087 2758);
PAINT GREEN (-6087 2758);
FORCEPROP 2 LAST CDS_LIB mstr_standard
J 0
(-6025 2750);
DISPLAY 0.723404 (-6025 2750);
PAINT MONO (-6025 2750);
DISPLAY INVISIBLE (-6025 2750);
FORCEPROP 1 LAST BODY_TYPE PLUMBING
J 0
(-6025 2800);
DISPLAY 0.872340 (-6025 2800);
PAINT GREEN (-6025 2800);
DISPLAY INVISIBLE (-6025 2800);
FORCEPROP 1 LAST HDL_TAP TRUE
J 0
(-5700 2625);
DISPLAY 0.872340 (-5700 2625);
DISPLAY INVISIBLE (-5700 2625);
FORCEPROP 1 LAST PATH I47
J 0
(-6027 2750);
DISPLAY 0.872340 (-6027 2750);
PAINT GREEN (-6027 2750);
DISPLAY INVISIBLE (-6027 2750);
FORCEADD TAP..1
(-6025 2800);
FORCEPROP 3 LASTPIN (-6075 2800) SIG_NAME M_H_CPU0_SB_DQ<13>
J 0
(-6065 2810);
DISPLAY 0.659574 (-6065 2810);
PAINT MONO (-6065 2810);
DISPLAY INVISIBLE (-6065 2810);
FORCEPROP 1 LASTPIN (-6075 2800) BN 13
J 0
(-6087 2808);
DISPLAY 0.489362 (-6087 2808);
PAINT GREEN (-6087 2808);
FORCEPROP 2 LAST CDS_LIB mstr_standard
J 0
(-6025 2800);
DISPLAY 0.723404 (-6025 2800);
PAINT MONO (-6025 2800);
DISPLAY INVISIBLE (-6025 2800);
FORCEPROP 1 LAST BODY_TYPE PLUMBING
J 0
(-6025 2850);
DISPLAY 0.872340 (-6025 2850);
PAINT GREEN (-6025 2850);
DISPLAY INVISIBLE (-6025 2850);
FORCEPROP 1 LAST HDL_TAP TRUE
J 0
(-5700 2675);
DISPLAY 0.872340 (-5700 2675);
DISPLAY INVISIBLE (-5700 2675);
FORCEPROP 1 LAST PATH I48
J 0
(-6027 2800);
DISPLAY 0.872340 (-6027 2800);
PAINT GREEN (-6027 2800);
DISPLAY INVISIBLE (-6027 2800);
FORCEADD TAP..1
(-6025 2850);
FORCEPROP 3 LASTPIN (-6075 2850) SIG_NAME M_H_CPU0_SB_DQ<14>
J 0
(-6065 2860);
DISPLAY 0.659574 (-6065 2860);
PAINT MONO (-6065 2860);
DISPLAY INVISIBLE (-6065 2860);
FORCEPROP 1 LASTPIN (-6075 2850) BN 14
J 0
(-6087 2858);
DISPLAY 0.489362 (-6087 2858);
PAINT GREEN (-6087 2858);
FORCEPROP 2 LAST CDS_LIB mstr_standard
J 0
(-6025 2850);
DISPLAY 0.723404 (-6025 2850);
PAINT MONO (-6025 2850);
DISPLAY INVISIBLE (-6025 2850);
FORCEPROP 1 LAST BODY_TYPE PLUMBING
J 0
(-6025 2900);
DISPLAY 0.872340 (-6025 2900);
PAINT GREEN (-6025 2900);
DISPLAY INVISIBLE (-6025 2900);
FORCEPROP 1 LAST HDL_TAP TRUE
J 0
(-5700 2725);
DISPLAY 0.872340 (-5700 2725);
DISPLAY INVISIBLE (-5700 2725);
FORCEPROP 1 LAST PATH I49
J 0
(-6027 2850);
DISPLAY 0.872340 (-6027 2850);
PAINT GREEN (-6027 2850);
DISPLAY INVISIBLE (-6027 2850);
FORCEADD VCC_CORE..1
(-8550 3375);
FORCEPROP 3 LASTPIN (-8550 3325) SIG_NAME P3V3_AUX\g
J 0
(-8540 3335);
DISPLAY 0.659574 (-8540 3335);
PAINT MONO (-8540 3335);
DISPLAY INVISIBLE (-8540 3335);
FORCEPROP 1 LAST HDL_POWER P3V3_AUX
J 1
(-8550 3425);
DISPLAY 0.489362 (-8550 3425);
PAINT GREEN (-8550 3425);
FORCEPROP 2 LAST ROOM PVCCINFAON_CPU0_CTRL
J 0
(-8550 3475);
DISPLAY 0.808511 (-8550 3475);
PAINT RED (-8550 3475);
DISPLAY INVISIBLE (-8550 3475);
FORCEPROP 0 LAST VOLTAGE 3.3
J 0
(-8825 3525);
DISPLAY 1.021277 (-8825 3525);
PAINT SKYBLUE (-8825 3525);
DISPLAY INVISIBLE (-8825 3525);
FORCEPROP 2 LAST CDS_LIB mstr_symbols
J 0
(-8550 3375);
PAINT MONO (-8550 3375);
DISPLAY INVISIBLE (-8550 3375);
FORCEPROP 1 LAST PATH I5
J 0
(-8500 3400);
DISPLAY 0.872340 (-8500 3400);
PAINT AQUA (-8500 3400);
DISPLAY INVISIBLE (-8500 3400);
FORCEADD TAP..1
(-6025 2950);
FORCEPROP 3 LASTPIN (-6075 2950) SIG_NAME M_H_CPU0_SB_DQ<16>
J 0
(-6065 2960);
DISPLAY 0.659574 (-6065 2960);
PAINT MONO (-6065 2960);
DISPLAY INVISIBLE (-6065 2960);
FORCEPROP 1 LASTPIN (-6075 2950) BN 16
J 0
(-6087 2958);
DISPLAY 0.489362 (-6087 2958);
PAINT GREEN (-6087 2958);
FORCEPROP 2 LAST CDS_LIB mstr_standard
J 0
(-6025 2950);
DISPLAY 0.723404 (-6025 2950);
PAINT MONO (-6025 2950);
DISPLAY INVISIBLE (-6025 2950);
FORCEPROP 1 LAST BODY_TYPE PLUMBING
J 0
(-6025 3000);
DISPLAY 0.872340 (-6025 3000);
PAINT GREEN (-6025 3000);
DISPLAY INVISIBLE (-6025 3000);
FORCEPROP 1 LAST HDL_TAP TRUE
J 0
(-5700 2825);
DISPLAY 0.872340 (-5700 2825);
DISPLAY INVISIBLE (-5700 2825);
FORCEPROP 1 LAST PATH I50
J 0
(-6027 2950);
DISPLAY 0.872340 (-6027 2950);
PAINT GREEN (-6027 2950);
DISPLAY INVISIBLE (-6027 2950);
FORCEADD TAP..1
(-6025 2900);
FORCEPROP 3 LASTPIN (-6075 2900) SIG_NAME M_H_CPU0_SB_DQ<15>
J 0
(-6065 2910);
DISPLAY 0.659574 (-6065 2910);
PAINT MONO (-6065 2910);
DISPLAY INVISIBLE (-6065 2910);
FORCEPROP 1 LASTPIN (-6075 2900) BN 15
J 0
(-6087 2908);
DISPLAY 0.489362 (-6087 2908);
PAINT GREEN (-6087 2908);
FORCEPROP 2 LAST CDS_LIB mstr_standard
J 0
(-6025 2900);
DISPLAY 0.723404 (-6025 2900);
PAINT MONO (-6025 2900);
DISPLAY INVISIBLE (-6025 2900);
FORCEPROP 1 LAST BODY_TYPE PLUMBING
J 0
(-6025 2950);
DISPLAY 0.872340 (-6025 2950);
PAINT GREEN (-6025 2950);
DISPLAY INVISIBLE (-6025 2950);
FORCEPROP 1 LAST HDL_TAP TRUE
J 0
(-5700 2775);
DISPLAY 0.872340 (-5700 2775);
DISPLAY INVISIBLE (-5700 2775);
FORCEPROP 1 LAST PATH I51
J 0
(-6027 2900);
DISPLAY 0.872340 (-6027 2900);
PAINT GREEN (-6027 2900);
DISPLAY INVISIBLE (-6027 2900);
FORCEADD TAP..1
(-6025 3000);
FORCEPROP 3 LASTPIN (-6075 3000) SIG_NAME M_H_CPU0_SB_DQ<17>
J 0
(-6065 3010);
DISPLAY 0.659574 (-6065 3010);
PAINT MONO (-6065 3010);
DISPLAY INVISIBLE (-6065 3010);
FORCEPROP 1 LASTPIN (-6075 3000) BN 17
J 0
(-6087 3008);
DISPLAY 0.489362 (-6087 3008);
PAINT GREEN (-6087 3008);
FORCEPROP 2 LAST CDS_LIB mstr_standard
J 0
(-6025 3000);
DISPLAY 0.723404 (-6025 3000);
PAINT MONO (-6025 3000);
DISPLAY INVISIBLE (-6025 3000);
FORCEPROP 1 LAST BODY_TYPE PLUMBING
J 0
(-6025 3050);
DISPLAY 0.872340 (-6025 3050);
PAINT GREEN (-6025 3050);
DISPLAY INVISIBLE (-6025 3050);
FORCEPROP 1 LAST HDL_TAP TRUE
J 0
(-5700 2875);
DISPLAY 0.872340 (-5700 2875);
DISPLAY INVISIBLE (-5700 2875);
FORCEPROP 1 LAST PATH I52
J 0
(-6027 3000);
DISPLAY 0.872340 (-6027 3000);
PAINT GREEN (-6027 3000);
DISPLAY INVISIBLE (-6027 3000);
FORCEADD TAP..1
(-6025 3100);
FORCEPROP 3 LASTPIN (-6075 3100) SIG_NAME M_H_CPU0_SB_DQ<19>
J 0
(-6065 3110);
DISPLAY 0.659574 (-6065 3110);
PAINT MONO (-6065 3110);
DISPLAY INVISIBLE (-6065 3110);
FORCEPROP 1 LASTPIN (-6075 3100) BN 19
J 0
(-6087 3108);
DISPLAY 0.489362 (-6087 3108);
PAINT GREEN (-6087 3108);
FORCEPROP 2 LAST CDS_LIB mstr_standard
J 0
(-6025 3100);
DISPLAY 0.723404 (-6025 3100);
PAINT MONO (-6025 3100);
DISPLAY INVISIBLE (-6025 3100);
FORCEPROP 1 LAST BODY_TYPE PLUMBING
J 0
(-6025 3150);
DISPLAY 0.872340 (-6025 3150);
PAINT GREEN (-6025 3150);
DISPLAY INVISIBLE (-6025 3150);
FORCEPROP 1 LAST HDL_TAP TRUE
J 0
(-5700 2975);
DISPLAY 0.872340 (-5700 2975);
DISPLAY INVISIBLE (-5700 2975);
FORCEPROP 1 LAST PATH I53
J 0
(-6027 3100);
DISPLAY 0.872340 (-6027 3100);
PAINT GREEN (-6027 3100);
DISPLAY INVISIBLE (-6027 3100);
FORCEADD TAP..1
(-6025 3150);
FORCEPROP 3 LASTPIN (-6075 3150) SIG_NAME M_H_CPU0_SB_DQ<20>
J 0
(-6065 3160);
DISPLAY 0.659574 (-6065 3160);
PAINT MONO (-6065 3160);
DISPLAY INVISIBLE (-6065 3160);
FORCEPROP 1 LASTPIN (-6075 3150) BN 20
J 0
(-6087 3158);
DISPLAY 0.489362 (-6087 3158);
PAINT GREEN (-6087 3158);
FORCEPROP 2 LAST CDS_LIB mstr_standard
J 0
(-6025 3150);
DISPLAY 0.723404 (-6025 3150);
PAINT MONO (-6025 3150);
DISPLAY INVISIBLE (-6025 3150);
FORCEPROP 1 LAST BODY_TYPE PLUMBING
J 0
(-6025 3200);
DISPLAY 0.872340 (-6025 3200);
PAINT GREEN (-6025 3200);
DISPLAY INVISIBLE (-6025 3200);
FORCEPROP 1 LAST HDL_TAP TRUE
J 0
(-5700 3025);
DISPLAY 0.872340 (-5700 3025);
DISPLAY INVISIBLE (-5700 3025);
FORCEPROP 1 LAST PATH I54
J 0
(-6027 3150);
DISPLAY 0.872340 (-6027 3150);
PAINT GREEN (-6027 3150);
DISPLAY INVISIBLE (-6027 3150);
FORCEADD TAP..1
(-6025 3250);
FORCEPROP 3 LASTPIN (-6075 3250) SIG_NAME M_H_CPU0_SB_DQ<22>
J 0
(-6065 3260);
DISPLAY 0.659574 (-6065 3260);
PAINT MONO (-6065 3260);
DISPLAY INVISIBLE (-6065 3260);
FORCEPROP 1 LASTPIN (-6075 3250) BN 22
J 0
(-6087 3258);
DISPLAY 0.489362 (-6087 3258);
PAINT GREEN (-6087 3258);
FORCEPROP 2 LAST CDS_LIB mstr_standard
J 0
(-6025 3250);
DISPLAY 0.723404 (-6025 3250);
PAINT MONO (-6025 3250);
DISPLAY INVISIBLE (-6025 3250);
FORCEPROP 1 LAST BODY_TYPE PLUMBING
J 0
(-6025 3300);
DISPLAY 0.872340 (-6025 3300);
PAINT GREEN (-6025 3300);
DISPLAY INVISIBLE (-6025 3300);
FORCEPROP 1 LAST HDL_TAP TRUE
J 0
(-5700 3125);
DISPLAY 0.872340 (-5700 3125);
DISPLAY INVISIBLE (-5700 3125);
FORCEPROP 1 LAST PATH I55
J 0
(-6027 3250);
DISPLAY 0.872340 (-6027 3250);
PAINT GREEN (-6027 3250);
DISPLAY INVISIBLE (-6027 3250);
FORCEADD TAP..1
(-6025 3200);
FORCEPROP 3 LASTPIN (-6075 3200) SIG_NAME M_H_CPU0_SB_DQ<21>
J 0
(-6065 3210);
DISPLAY 0.659574 (-6065 3210);
PAINT MONO (-6065 3210);
DISPLAY INVISIBLE (-6065 3210);
FORCEPROP 1 LASTPIN (-6075 3200) BN 21
J 0
(-6087 3208);
DISPLAY 0.489362 (-6087 3208);
PAINT GREEN (-6087 3208);
FORCEPROP 2 LAST CDS_LIB mstr_standard
J 0
(-6025 3200);
DISPLAY 0.723404 (-6025 3200);
PAINT MONO (-6025 3200);
DISPLAY INVISIBLE (-6025 3200);
FORCEPROP 1 LAST BODY_TYPE PLUMBING
J 0
(-6025 3250);
DISPLAY 0.872340 (-6025 3250);
PAINT GREEN (-6025 3250);
DISPLAY INVISIBLE (-6025 3250);
FORCEPROP 1 LAST HDL_TAP TRUE
J 0
(-5700 3075);
DISPLAY 0.872340 (-5700 3075);
DISPLAY INVISIBLE (-5700 3075);
FORCEPROP 1 LAST PATH I56
J 0
(-6027 3200);
DISPLAY 0.872340 (-6027 3200);
PAINT GREEN (-6027 3200);
DISPLAY INVISIBLE (-6027 3200);
FORCEADD TAP..1
(-6025 3050);
FORCEPROP 3 LASTPIN (-6075 3050) SIG_NAME M_H_CPU0_SB_DQ<18>
J 0
(-6065 3060);
DISPLAY 0.659574 (-6065 3060);
PAINT MONO (-6065 3060);
DISPLAY INVISIBLE (-6065 3060);
FORCEPROP 1 LASTPIN (-6075 3050) BN 18
J 0
(-6087 3058);
DISPLAY 0.489362 (-6087 3058);
PAINT GREEN (-6087 3058);
FORCEPROP 2 LAST CDS_LIB mstr_standard
J 0
(-6025 3050);
DISPLAY 0.723404 (-6025 3050);
PAINT MONO (-6025 3050);
DISPLAY INVISIBLE (-6025 3050);
FORCEPROP 1 LAST BODY_TYPE PLUMBING
J 0
(-6025 3100);
DISPLAY 0.872340 (-6025 3100);
PAINT GREEN (-6025 3100);
DISPLAY INVISIBLE (-6025 3100);
FORCEPROP 1 LAST HDL_TAP TRUE
J 0
(-5700 2925);
DISPLAY 0.872340 (-5700 2925);
DISPLAY INVISIBLE (-5700 2925);
FORCEPROP 1 LAST PATH I57
J 0
(-6027 3050);
DISPLAY 0.872340 (-6027 3050);
PAINT GREEN (-6027 3050);
DISPLAY INVISIBLE (-6027 3050);
FORCEADD TAP..1
(-6025 3350);
FORCEPROP 3 LASTPIN (-6075 3350) SIG_NAME M_H_CPU0_SB_DQ<24>
J 0
(-6065 3360);
DISPLAY 0.659574 (-6065 3360);
PAINT MONO (-6065 3360);
DISPLAY INVISIBLE (-6065 3360);
FORCEPROP 1 LASTPIN (-6075 3350) BN 24
J 0
(-6087 3358);
DISPLAY 0.489362 (-6087 3358);
PAINT GREEN (-6087 3358);
FORCEPROP 2 LAST CDS_LIB mstr_standard
J 0
(-6025 3350);
DISPLAY 0.723404 (-6025 3350);
PAINT MONO (-6025 3350);
DISPLAY INVISIBLE (-6025 3350);
FORCEPROP 1 LAST BODY_TYPE PLUMBING
J 0
(-6025 3400);
DISPLAY 0.872340 (-6025 3400);
PAINT GREEN (-6025 3400);
DISPLAY INVISIBLE (-6025 3400);
FORCEPROP 1 LAST HDL_TAP TRUE
J 0
(-5700 3225);
DISPLAY 0.872340 (-5700 3225);
DISPLAY INVISIBLE (-5700 3225);
FORCEPROP 1 LAST PATH I58
J 0
(-6027 3350);
DISPLAY 0.872340 (-6027 3350);
PAINT GREEN (-6027 3350);
DISPLAY INVISIBLE (-6027 3350);
FORCEADD TAP..1
(-6025 3400);
FORCEPROP 3 LASTPIN (-6075 3400) SIG_NAME M_H_CPU0_SB_DQ<25>
J 0
(-6065 3410);
DISPLAY 0.659574 (-6065 3410);
PAINT MONO (-6065 3410);
DISPLAY INVISIBLE (-6065 3410);
FORCEPROP 1 LASTPIN (-6075 3400) BN 25
J 0
(-6087 3408);
DISPLAY 0.489362 (-6087 3408);
PAINT GREEN (-6087 3408);
FORCEPROP 2 LAST CDS_LIB mstr_standard
J 0
(-6025 3400);
DISPLAY 0.723404 (-6025 3400);
PAINT MONO (-6025 3400);
DISPLAY INVISIBLE (-6025 3400);
FORCEPROP 1 LAST BODY_TYPE PLUMBING
J 0
(-6025 3450);
DISPLAY 0.872340 (-6025 3450);
PAINT GREEN (-6025 3450);
DISPLAY INVISIBLE (-6025 3450);
FORCEPROP 1 LAST HDL_TAP TRUE
J 0
(-5700 3275);
DISPLAY 0.872340 (-5700 3275);
DISPLAY INVISIBLE (-5700 3275);
FORCEPROP 1 LAST PATH I59
J 0
(-6027 3400);
DISPLAY 0.872340 (-6027 3400);
PAINT GREEN (-6027 3400);
DISPLAY INVISIBLE (-6027 3400);
FORCEADD TAP..1
(-6025 3500);
FORCEPROP 3 LASTPIN (-6075 3500) SIG_NAME M_H_CPU0_SB_DQ<27>
J 0
(-6065 3510);
DISPLAY 0.659574 (-6065 3510);
PAINT MONO (-6065 3510);
DISPLAY INVISIBLE (-6065 3510);
FORCEPROP 1 LASTPIN (-6075 3500) BN 27
J 0
(-6087 3508);
DISPLAY 0.489362 (-6087 3508);
PAINT GREEN (-6087 3508);
FORCEPROP 2 LAST CDS_LIB mstr_standard
J 0
(-6025 3500);
DISPLAY 0.723404 (-6025 3500);
PAINT MONO (-6025 3500);
DISPLAY INVISIBLE (-6025 3500);
FORCEPROP 1 LAST BODY_TYPE PLUMBING
J 0
(-6025 3550);
DISPLAY 0.872340 (-6025 3550);
PAINT GREEN (-6025 3550);
DISPLAY INVISIBLE (-6025 3550);
FORCEPROP 1 LAST HDL_TAP TRUE
J 0
(-5700 3375);
DISPLAY 0.872340 (-5700 3375);
DISPLAY INVISIBLE (-5700 3375);
FORCEPROP 1 LAST PATH I60
J 0
(-6027 3500);
DISPLAY 0.872340 (-6027 3500);
PAINT GREEN (-6027 3500);
DISPLAY INVISIBLE (-6027 3500);
FORCEADD TAP..1
(-6025 3450);
FORCEPROP 3 LASTPIN (-6075 3450) SIG_NAME M_H_CPU0_SB_DQ<26>
J 0
(-6065 3460);
DISPLAY 0.659574 (-6065 3460);
PAINT MONO (-6065 3460);
DISPLAY INVISIBLE (-6065 3460);
FORCEPROP 1 LASTPIN (-6075 3450) BN 26
J 0
(-6087 3458);
DISPLAY 0.489362 (-6087 3458);
PAINT GREEN (-6087 3458);
FORCEPROP 2 LAST CDS_LIB mstr_standard
J 0
(-6025 3450);
DISPLAY 0.723404 (-6025 3450);
PAINT MONO (-6025 3450);
DISPLAY INVISIBLE (-6025 3450);
FORCEPROP 1 LAST BODY_TYPE PLUMBING
J 0
(-6025 3500);
DISPLAY 0.872340 (-6025 3500);
PAINT GREEN (-6025 3500);
DISPLAY INVISIBLE (-6025 3500);
FORCEPROP 1 LAST HDL_TAP TRUE
J 0
(-5700 3325);
DISPLAY 0.872340 (-5700 3325);
DISPLAY INVISIBLE (-5700 3325);
FORCEPROP 1 LAST PATH I61
J 0
(-6027 3450);
DISPLAY 0.872340 (-6027 3450);
PAINT GREEN (-6027 3450);
DISPLAY INVISIBLE (-6027 3450);
FORCEADD TAP..1
(-6025 3300);
FORCEPROP 3 LASTPIN (-6075 3300) SIG_NAME M_H_CPU0_SB_DQ<23>
J 0
(-6065 3310);
DISPLAY 0.659574 (-6065 3310);
PAINT MONO (-6065 3310);
DISPLAY INVISIBLE (-6065 3310);
FORCEPROP 1 LASTPIN (-6075 3300) BN 23
J 0
(-6087 3308);
DISPLAY 0.489362 (-6087 3308);
PAINT GREEN (-6087 3308);
FORCEPROP 2 LAST CDS_LIB mstr_standard
J 0
(-6025 3300);
DISPLAY 0.723404 (-6025 3300);
PAINT MONO (-6025 3300);
DISPLAY INVISIBLE (-6025 3300);
FORCEPROP 1 LAST BODY_TYPE PLUMBING
J 0
(-6025 3350);
DISPLAY 0.872340 (-6025 3350);
PAINT GREEN (-6025 3350);
DISPLAY INVISIBLE (-6025 3350);
FORCEPROP 1 LAST HDL_TAP TRUE
J 0
(-5700 3175);
DISPLAY 0.872340 (-5700 3175);
DISPLAY INVISIBLE (-5700 3175);
FORCEPROP 1 LAST PATH I62
J 0
(-6027 3300);
DISPLAY 0.872340 (-6027 3300);
PAINT GREEN (-6027 3300);
DISPLAY INVISIBLE (-6027 3300);
FORCEADD TAP..1
(-6025 3600);
FORCEPROP 3 LASTPIN (-6075 3600) SIG_NAME M_H_CPU0_SB_DQ<29>
J 0
(-6065 3610);
DISPLAY 0.659574 (-6065 3610);
PAINT MONO (-6065 3610);
DISPLAY INVISIBLE (-6065 3610);
FORCEPROP 1 LASTPIN (-6075 3600) BN 29
J 0
(-6087 3608);
DISPLAY 0.489362 (-6087 3608);
PAINT GREEN (-6087 3608);
FORCEPROP 2 LAST CDS_LIB mstr_standard
J 0
(-6025 3600);
DISPLAY 0.723404 (-6025 3600);
PAINT MONO (-6025 3600);
DISPLAY INVISIBLE (-6025 3600);
FORCEPROP 1 LAST BODY_TYPE PLUMBING
J 0
(-6025 3650);
DISPLAY 0.872340 (-6025 3650);
PAINT GREEN (-6025 3650);
DISPLAY INVISIBLE (-6025 3650);
FORCEPROP 1 LAST HDL_TAP TRUE
J 0
(-5700 3475);
DISPLAY 0.872340 (-5700 3475);
DISPLAY INVISIBLE (-5700 3475);
FORCEPROP 1 LAST PATH I63
J 0
(-6027 3600);
DISPLAY 0.872340 (-6027 3600);
PAINT GREEN (-6027 3600);
DISPLAY INVISIBLE (-6027 3600);
FORCEADD TAP..1
(-6025 3700);
FORCEPROP 3 LASTPIN (-6075 3700) SIG_NAME M_H_CPU0_SB_DQ<31>
J 0
(-6065 3710);
DISPLAY 0.659574 (-6065 3710);
PAINT MONO (-6065 3710);
DISPLAY INVISIBLE (-6065 3710);
FORCEPROP 1 LASTPIN (-6075 3700) BN 31
J 0
(-6087 3708);
DISPLAY 0.489362 (-6087 3708);
PAINT GREEN (-6087 3708);
FORCEPROP 2 LAST CDS_LIB mstr_standard
J 0
(-6025 3700);
DISPLAY 0.723404 (-6025 3700);
PAINT MONO (-6025 3700);
DISPLAY INVISIBLE (-6025 3700);
FORCEPROP 1 LAST BODY_TYPE PLUMBING
J 0
(-6025 3750);
DISPLAY 0.872340 (-6025 3750);
PAINT GREEN (-6025 3750);
DISPLAY INVISIBLE (-6025 3750);
FORCEPROP 1 LAST HDL_TAP TRUE
J 0
(-5700 3575);
DISPLAY 0.872340 (-5700 3575);
DISPLAY INVISIBLE (-5700 3575);
FORCEPROP 1 LAST PATH I64
J 0
(-6027 3700);
DISPLAY 0.872340 (-6027 3700);
PAINT GREEN (-6027 3700);
DISPLAY INVISIBLE (-6027 3700);
FORCEADD TAP..1
(-6025 3650);
FORCEPROP 3 LASTPIN (-6075 3650) SIG_NAME M_H_CPU0_SB_DQ<30>
J 0
(-6065 3660);
DISPLAY 0.659574 (-6065 3660);
PAINT MONO (-6065 3660);
DISPLAY INVISIBLE (-6065 3660);
FORCEPROP 1 LASTPIN (-6075 3650) BN 30
J 0
(-6087 3658);
DISPLAY 0.489362 (-6087 3658);
PAINT GREEN (-6087 3658);
FORCEPROP 2 LAST CDS_LIB mstr_standard
J 0
(-6025 3650);
DISPLAY 0.723404 (-6025 3650);
PAINT MONO (-6025 3650);
DISPLAY INVISIBLE (-6025 3650);
FORCEPROP 1 LAST BODY_TYPE PLUMBING
J 0
(-6025 3700);
DISPLAY 0.872340 (-6025 3700);
PAINT GREEN (-6025 3700);
DISPLAY INVISIBLE (-6025 3700);
FORCEPROP 1 LAST HDL_TAP TRUE
J 0
(-5700 3525);
DISPLAY 0.872340 (-5700 3525);
DISPLAY INVISIBLE (-5700 3525);
FORCEPROP 1 LAST PATH I65
J 0
(-6027 3650);
DISPLAY 0.872340 (-6027 3650);
PAINT GREEN (-6027 3650);
DISPLAY INVISIBLE (-6027 3650);
FORCEADD TAP..1
(-6025 3550);
FORCEPROP 3 LASTPIN (-6075 3550) SIG_NAME M_H_CPU0_SB_DQ<28>
J 0
(-6065 3560);
DISPLAY 0.659574 (-6065 3560);
PAINT MONO (-6065 3560);
DISPLAY INVISIBLE (-6065 3560);
FORCEPROP 1 LASTPIN (-6075 3550) BN 28
J 0
(-6087 3558);
DISPLAY 0.489362 (-6087 3558);
PAINT GREEN (-6087 3558);
FORCEPROP 2 LAST CDS_LIB mstr_standard
J 0
(-6025 3550);
DISPLAY 0.723404 (-6025 3550);
PAINT MONO (-6025 3550);
DISPLAY INVISIBLE (-6025 3550);
FORCEPROP 1 LAST BODY_TYPE PLUMBING
J 0
(-6025 3600);
DISPLAY 0.872340 (-6025 3600);
PAINT GREEN (-6025 3600);
DISPLAY INVISIBLE (-6025 3600);
FORCEPROP 1 LAST HDL_TAP TRUE
J 0
(-5700 3425);
DISPLAY 0.872340 (-5700 3425);
DISPLAY INVISIBLE (-5700 3425);
FORCEPROP 1 LAST PATH I66
J 0
(-6027 3550);
DISPLAY 0.872340 (-6027 3550);
PAINT GREEN (-6027 3550);
DISPLAY INVISIBLE (-6027 3550);
FORCEADD OFFPAGE..3
(-5350 3750);
FORCEPROP 2 LAST $XR0 17 
J 0
(-5136 3750);
DISPLAY 0.638298 (-5136 3750);
PAINT MONO (-5136 3750);
FORCEPROP 2 LAST CDS_LIB mstr_standard
J 0
(-5350 3750);
DISPLAY 0.723404 (-5350 3750);
PAINT MONO (-5350 3750);
DISPLAY INVISIBLE (-5350 3750);
FORCEPROP 1 LAST OFFPAGE TRUE
J 0
(-5025 3625);
DISPLAY 0.872340 (-5025 3625);
PAINT GREEN (-5025 3625);
DISPLAY INVISIBLE (-5025 3625);
FORCEPROP 1 LAST COMMENT_BODY TRUE
J 0
(-5400 3650);
DISPLAY 0.872340 (-5400 3650);
PAINT GREEN (-5400 3650);
DISPLAY INVISIBLE (-5400 3650);
FORCEPROP 2 LAST PATH I73
J 0
(-5150 3825);
DISPLAY 1.021277 (-5150 3825);
DISPLAY INVISIBLE (-5150 3825);
FORCEADD TAP..1
R 2
(-7725 3800);
FORCEPROP 3 LASTPIN (-7675 3800) SIG_NAME M_H_CPU0_SA_CB<4>
J 0
(-7665 3810);
DISPLAY 0.659574 (-7665 3810);
PAINT MONO (-7665 3810);
DISPLAY INVISIBLE (-7665 3810);
FORCEPROP 1 LASTPIN (-7675 3800) BN 4
J 2
(-7663 3808);
DISPLAY 0.489362 (-7663 3808);
PAINT GREEN (-7663 3808);
FORCEPROP 2 LAST CDS_LIB mstr_standard
J 0
(-7725 3800);
DISPLAY 0.723404 (-7725 3800);
PAINT MONO (-7725 3800);
DISPLAY INVISIBLE (-7725 3800);
FORCEPROP 1 LAST BODY_TYPE PLUMBING
J 2
(-7725 3850);
DISPLAY 0.872340 (-7725 3850);
PAINT GREEN (-7725 3850);
DISPLAY INVISIBLE (-7725 3850);
FORCEPROP 1 LAST HDL_TAP TRUE
J 2
(-8050 3675);
DISPLAY 0.872340 (-8050 3675);
DISPLAY INVISIBLE (-8050 3675);
FORCEPROP 1 LAST PATH I76
J 2
(-7723 3800);
DISPLAY 0.872340 (-7723 3800);
PAINT GREEN (-7723 3800);
DISPLAY INVISIBLE (-7723 3800);
FORCEADD TAP..1
R 2
(-7725 3850);
FORCEPROP 3 LASTPIN (-7675 3850) SIG_NAME M_H_CPU0_SA_CB<5>
J 0
(-7665 3860);
DISPLAY 0.659574 (-7665 3860);
PAINT MONO (-7665 3860);
DISPLAY INVISIBLE (-7665 3860);
FORCEPROP 1 LASTPIN (-7675 3850) BN 5
J 2
(-7663 3858);
DISPLAY 0.489362 (-7663 3858);
PAINT GREEN (-7663 3858);
FORCEPROP 2 LAST CDS_LIB mstr_standard
J 0
(-7725 3850);
DISPLAY 0.723404 (-7725 3850);
PAINT MONO (-7725 3850);
DISPLAY INVISIBLE (-7725 3850);
FORCEPROP 1 LAST BODY_TYPE PLUMBING
J 2
(-7725 3900);
DISPLAY 0.872340 (-7725 3900);
PAINT GREEN (-7725 3900);
DISPLAY INVISIBLE (-7725 3900);
FORCEPROP 1 LAST HDL_TAP TRUE
J 2
(-8050 3725);
DISPLAY 0.872340 (-8050 3725);
DISPLAY INVISIBLE (-8050 3725);
FORCEPROP 1 LAST PATH I77
J 2
(-7723 3850);
DISPLAY 0.872340 (-7723 3850);
PAINT GREEN (-7723 3850);
DISPLAY INVISIBLE (-7723 3850);
FORCEADD TAP..1
R 2
(-7725 3950);
FORCEPROP 3 LASTPIN (-7675 3950) SIG_NAME M_H_CPU0_SA_CB<7>
J 0
(-7665 3960);
DISPLAY 0.659574 (-7665 3960);
PAINT MONO (-7665 3960);
DISPLAY INVISIBLE (-7665 3960);
FORCEPROP 1 LASTPIN (-7675 3950) BN 7
J 2
(-7663 3958);
DISPLAY 0.489362 (-7663 3958);
PAINT GREEN (-7663 3958);
FORCEPROP 2 LAST CDS_LIB mstr_standard
J 0
(-7725 3950);
DISPLAY 0.723404 (-7725 3950);
PAINT MONO (-7725 3950);
DISPLAY INVISIBLE (-7725 3950);
FORCEPROP 1 LAST BODY_TYPE PLUMBING
J 2
(-7725 4000);
DISPLAY 0.872340 (-7725 4000);
PAINT GREEN (-7725 4000);
DISPLAY INVISIBLE (-7725 4000);
FORCEPROP 1 LAST HDL_TAP TRUE
J 2
(-8050 3825);
DISPLAY 0.872340 (-8050 3825);
DISPLAY INVISIBLE (-8050 3825);
FORCEPROP 1 LAST PATH I78
J 2
(-7723 3950);
DISPLAY 0.872340 (-7723 3950);
PAINT GREEN (-7723 3950);
DISPLAY INVISIBLE (-7723 3950);
FORCEADD TAP..1
R 2
(-7725 3900);
FORCEPROP 3 LASTPIN (-7675 3900) SIG_NAME M_H_CPU0_SA_CB<6>
J 0
(-7665 3910);
DISPLAY 0.659574 (-7665 3910);
PAINT MONO (-7665 3910);
DISPLAY INVISIBLE (-7665 3910);
FORCEPROP 1 LASTPIN (-7675 3900) BN 6
J 2
(-7663 3908);
DISPLAY 0.489362 (-7663 3908);
PAINT GREEN (-7663 3908);
FORCEPROP 2 LAST CDS_LIB mstr_standard
J 0
(-7725 3900);
DISPLAY 0.723404 (-7725 3900);
PAINT MONO (-7725 3900);
DISPLAY INVISIBLE (-7725 3900);
FORCEPROP 1 LAST BODY_TYPE PLUMBING
J 2
(-7725 3950);
DISPLAY 0.872340 (-7725 3950);
PAINT GREEN (-7725 3950);
DISPLAY INVISIBLE (-7725 3950);
FORCEPROP 1 LAST HDL_TAP TRUE
J 2
(-8050 3775);
DISPLAY 0.872340 (-8050 3775);
DISPLAY INVISIBLE (-8050 3775);
FORCEPROP 1 LAST PATH I79
J 2
(-7723 3900);
DISPLAY 0.872340 (-7723 3900);
PAINT GREEN (-7723 3900);
DISPLAY INVISIBLE (-7723 3900);
FORCEADD OFFPAGE..1
(-8475 2850);
FORCEPROP 2 LAST $XR0 93 
J 0
(-8726 2850);
DISPLAY 0.638298 (-8726 2850);
PAINT MONO (-8726 2850);
FORCEPROP 2 LAST CDS_LIB mstr_standard
J 0
(-8475 2850);
DISPLAY 0.808511 (-8475 2850);
DISPLAY INVISIBLE (-8475 2850);
FORCEPROP 1 LAST OFFPAGE TRUE
J 0
(-8150 2725);
DISPLAY 0.872340 (-8150 2725);
PAINT GREEN (-8150 2725);
DISPLAY INVISIBLE (-8150 2725);
FORCEPROP 1 LAST COMMENT_BODY TRUE
J 0
(-8350 2750);
DISPLAY 0.872340 (-8350 2750);
PAINT GREEN (-8350 2750);
DISPLAY INVISIBLE (-8350 2750);
FORCEPROP 2 LAST PATH I8
J 0
(-8725 2900);
DISPLAY 1.021277 (-8725 2900);
DISPLAY INVISIBLE (-8725 2900);
FORCEADD TAP..1
R 2
(-7725 4650);
FORCEPROP 3 LASTPIN (-7675 4650) SIG_NAME M_H_CPU0_SB_CA<0>
J 0
(-7665 4660);
DISPLAY 0.659574 (-7665 4660);
PAINT MONO (-7665 4660);
DISPLAY INVISIBLE (-7665 4660);
FORCEPROP 1 LASTPIN (-7675 4650) BN 0
J 2
(-7663 4658);
DISPLAY 0.489362 (-7663 4658);
PAINT GREEN (-7663 4658);
FORCEPROP 2 LAST CDS_LIB mstr_standard
J 0
(-7725 4650);
DISPLAY 0.723404 (-7725 4650);
PAINT MONO (-7725 4650);
DISPLAY INVISIBLE (-7725 4650);
FORCEPROP 1 LAST BODY_TYPE PLUMBING
J 2
(-7725 4700);
DISPLAY 0.872340 (-7725 4700);
PAINT GREEN (-7725 4700);
DISPLAY INVISIBLE (-7725 4700);
FORCEPROP 1 LAST HDL_TAP TRUE
J 2
(-8050 4525);
DISPLAY 0.872340 (-8050 4525);
DISPLAY INVISIBLE (-8050 4525);
FORCEPROP 1 LAST PATH I80
J 2
(-7723 4650);
DISPLAY 0.872340 (-7723 4650);
PAINT GREEN (-7723 4650);
DISPLAY INVISIBLE (-7723 4650);
FORCEADD TAP..1
R 2
(-7725 4700);
FORCEPROP 3 LASTPIN (-7675 4700) SIG_NAME M_H_CPU0_SB_CA<1>
J 0
(-7665 4710);
DISPLAY 0.659574 (-7665 4710);
PAINT MONO (-7665 4710);
DISPLAY INVISIBLE (-7665 4710);
FORCEPROP 1 LASTPIN (-7675 4700) BN 1
J 2
(-7663 4708);
DISPLAY 0.489362 (-7663 4708);
PAINT GREEN (-7663 4708);
FORCEPROP 2 LAST CDS_LIB mstr_standard
J 0
(-7725 4700);
DISPLAY 0.723404 (-7725 4700);
PAINT MONO (-7725 4700);
DISPLAY INVISIBLE (-7725 4700);
FORCEPROP 1 LAST BODY_TYPE PLUMBING
J 2
(-7725 4750);
DISPLAY 0.872340 (-7725 4750);
PAINT GREEN (-7725 4750);
DISPLAY INVISIBLE (-7725 4750);
FORCEPROP 1 LAST HDL_TAP TRUE
J 2
(-8050 4575);
DISPLAY 0.872340 (-8050 4575);
DISPLAY INVISIBLE (-8050 4575);
FORCEPROP 1 LAST PATH I81
J 2
(-7723 4700);
DISPLAY 0.872340 (-7723 4700);
PAINT GREEN (-7723 4700);
DISPLAY INVISIBLE (-7723 4700);
FORCEADD TAP..1
R 2
(-7725 4750);
FORCEPROP 3 LASTPIN (-7675 4750) SIG_NAME M_H_CPU0_SB_CA<2>
J 0
(-7665 4760);
DISPLAY 0.659574 (-7665 4760);
PAINT MONO (-7665 4760);
DISPLAY INVISIBLE (-7665 4760);
FORCEPROP 1 LASTPIN (-7675 4750) BN 2
J 2
(-7663 4758);
DISPLAY 0.489362 (-7663 4758);
PAINT GREEN (-7663 4758);
FORCEPROP 2 LAST CDS_LIB mstr_standard
J 0
(-7725 4750);
DISPLAY 0.723404 (-7725 4750);
PAINT MONO (-7725 4750);
DISPLAY INVISIBLE (-7725 4750);
FORCEPROP 1 LAST BODY_TYPE PLUMBING
J 2
(-7725 4800);
DISPLAY 0.872340 (-7725 4800);
PAINT GREEN (-7725 4800);
DISPLAY INVISIBLE (-7725 4800);
FORCEPROP 1 LAST HDL_TAP TRUE
J 2
(-8050 4625);
DISPLAY 0.872340 (-8050 4625);
DISPLAY INVISIBLE (-8050 4625);
FORCEPROP 1 LAST PATH I82
J 2
(-7723 4750);
DISPLAY 0.872340 (-7723 4750);
PAINT GREEN (-7723 4750);
DISPLAY INVISIBLE (-7723 4750);
FORCEADD TAP..1
R 2
(-7725 4850);
FORCEPROP 3 LASTPIN (-7675 4850) SIG_NAME M_H_CPU0_SB_CA<4>
J 0
(-7665 4860);
DISPLAY 0.659574 (-7665 4860);
PAINT MONO (-7665 4860);
DISPLAY INVISIBLE (-7665 4860);
FORCEPROP 1 LASTPIN (-7675 4850) BN 4
J 2
(-7663 4858);
DISPLAY 0.489362 (-7663 4858);
PAINT GREEN (-7663 4858);
FORCEPROP 2 LAST CDS_LIB mstr_standard
J 0
(-7725 4850);
DISPLAY 0.723404 (-7725 4850);
PAINT MONO (-7725 4850);
DISPLAY INVISIBLE (-7725 4850);
FORCEPROP 1 LAST BODY_TYPE PLUMBING
J 2
(-7725 4900);
DISPLAY 0.872340 (-7725 4900);
PAINT GREEN (-7725 4900);
DISPLAY INVISIBLE (-7725 4900);
FORCEPROP 1 LAST HDL_TAP TRUE
J 2
(-8050 4725);
DISPLAY 0.872340 (-8050 4725);
DISPLAY INVISIBLE (-8050 4725);
FORCEPROP 1 LAST PATH I83
J 2
(-7723 4850);
DISPLAY 0.872340 (-7723 4850);
PAINT GREEN (-7723 4850);
DISPLAY INVISIBLE (-7723 4850);
FORCEADD TAP..1
R 2
(-7725 4800);
FORCEPROP 3 LASTPIN (-7675 4800) SIG_NAME M_H_CPU0_SB_CA<3>
J 0
(-7665 4810);
DISPLAY 0.659574 (-7665 4810);
PAINT MONO (-7665 4810);
DISPLAY INVISIBLE (-7665 4810);
FORCEPROP 1 LASTPIN (-7675 4800) BN 3
J 2
(-7663 4808);
DISPLAY 0.489362 (-7663 4808);
PAINT GREEN (-7663 4808);
FORCEPROP 2 LAST CDS_LIB mstr_standard
J 0
(-7725 4800);
DISPLAY 0.723404 (-7725 4800);
PAINT MONO (-7725 4800);
DISPLAY INVISIBLE (-7725 4800);
FORCEPROP 1 LAST BODY_TYPE PLUMBING
J 2
(-7725 4850);
DISPLAY 0.872340 (-7725 4850);
PAINT GREEN (-7725 4850);
DISPLAY INVISIBLE (-7725 4850);
FORCEPROP 1 LAST HDL_TAP TRUE
J 2
(-8050 4675);
DISPLAY 0.872340 (-8050 4675);
DISPLAY INVISIBLE (-8050 4675);
FORCEPROP 1 LAST PATH I84
J 2
(-7723 4800);
DISPLAY 0.872340 (-7723 4800);
PAINT GREEN (-7723 4800);
DISPLAY INVISIBLE (-7723 4800);
FORCEADD TAP..1
R 2
(-7725 4900);
FORCEPROP 3 LASTPIN (-7675 4900) SIG_NAME M_H_CPU0_SB_CA<5>
J 0
(-7665 4910);
DISPLAY 0.659574 (-7665 4910);
PAINT MONO (-7665 4910);
DISPLAY INVISIBLE (-7665 4910);
FORCEPROP 1 LASTPIN (-7675 4900) BN 5
J 2
(-7663 4908);
DISPLAY 0.489362 (-7663 4908);
PAINT GREEN (-7663 4908);
FORCEPROP 2 LAST CDS_LIB mstr_standard
J 0
(-7725 4900);
DISPLAY 0.723404 (-7725 4900);
PAINT MONO (-7725 4900);
DISPLAY INVISIBLE (-7725 4900);
FORCEPROP 1 LAST BODY_TYPE PLUMBING
J 2
(-7725 4950);
DISPLAY 0.872340 (-7725 4950);
PAINT GREEN (-7725 4950);
DISPLAY INVISIBLE (-7725 4950);
FORCEPROP 1 LAST HDL_TAP TRUE
J 2
(-8050 4775);
DISPLAY 0.872340 (-8050 4775);
DISPLAY INVISIBLE (-8050 4775);
FORCEPROP 1 LAST PATH I85
J 2
(-7723 4900);
DISPLAY 0.872340 (-7723 4900);
PAINT GREEN (-7723 4900);
DISPLAY INVISIBLE (-7723 4900);
FORCEADD TAP..1
R 2
(-7725 4950);
FORCEPROP 3 LASTPIN (-7675 4950) SIG_NAME M_H_CPU0_SB_CA<6>
J 0
(-7665 4960);
DISPLAY 0.659574 (-7665 4960);
PAINT MONO (-7665 4960);
DISPLAY INVISIBLE (-7665 4960);
FORCEPROP 1 LASTPIN (-7675 4950) BN 6
J 2
(-7663 4958);
DISPLAY 0.489362 (-7663 4958);
PAINT GREEN (-7663 4958);
FORCEPROP 2 LAST CDS_LIB mstr_standard
J 0
(-7725 4950);
DISPLAY 0.723404 (-7725 4950);
PAINT MONO (-7725 4950);
DISPLAY INVISIBLE (-7725 4950);
FORCEPROP 1 LAST BODY_TYPE PLUMBING
J 2
(-7725 5000);
DISPLAY 0.872340 (-7725 5000);
PAINT GREEN (-7725 5000);
DISPLAY INVISIBLE (-7725 5000);
FORCEPROP 1 LAST HDL_TAP TRUE
J 2
(-8050 4825);
DISPLAY 0.872340 (-8050 4825);
DISPLAY INVISIBLE (-8050 4825);
FORCEPROP 1 LAST PATH I86
J 2
(-7723 4950);
DISPLAY 0.872340 (-7723 4950);
PAINT GREEN (-7723 4950);
DISPLAY INVISIBLE (-7723 4950);
FORCEADD TAP..1
R 2
(-7725 5050);
FORCEPROP 3 LASTPIN (-7675 5050) SIG_NAME M_H_CPU0_SA_CA<0>
J 0
(-7665 5060);
DISPLAY 0.659574 (-7665 5060);
PAINT MONO (-7665 5060);
DISPLAY INVISIBLE (-7665 5060);
FORCEPROP 1 LASTPIN (-7675 5050) BN 0
J 2
(-7663 5058);
DISPLAY 0.489362 (-7663 5058);
PAINT GREEN (-7663 5058);
FORCEPROP 2 LAST CDS_LIB mstr_standard
J 0
(-7725 5050);
DISPLAY 0.723404 (-7725 5050);
PAINT MONO (-7725 5050);
DISPLAY INVISIBLE (-7725 5050);
FORCEPROP 1 LAST BODY_TYPE PLUMBING
J 2
(-7725 5100);
DISPLAY 0.872340 (-7725 5100);
PAINT GREEN (-7725 5100);
DISPLAY INVISIBLE (-7725 5100);
FORCEPROP 1 LAST HDL_TAP TRUE
J 2
(-8050 4925);
DISPLAY 0.872340 (-8050 4925);
DISPLAY INVISIBLE (-8050 4925);
FORCEPROP 1 LAST PATH I87
J 2
(-7723 5050);
DISPLAY 0.872340 (-7723 5050);
PAINT GREEN (-7723 5050);
DISPLAY INVISIBLE (-7723 5050);
FORCEADD TAP..1
R 2
(-7725 5100);
FORCEPROP 3 LASTPIN (-7675 5100) SIG_NAME M_H_CPU0_SA_CA<1>
J 0
(-7665 5110);
DISPLAY 0.659574 (-7665 5110);
PAINT MONO (-7665 5110);
DISPLAY INVISIBLE (-7665 5110);
FORCEPROP 1 LASTPIN (-7675 5100) BN 1
J 2
(-7663 5108);
DISPLAY 0.489362 (-7663 5108);
PAINT GREEN (-7663 5108);
FORCEPROP 2 LAST CDS_LIB mstr_standard
J 0
(-7725 5100);
DISPLAY 0.723404 (-7725 5100);
PAINT MONO (-7725 5100);
DISPLAY INVISIBLE (-7725 5100);
FORCEPROP 1 LAST BODY_TYPE PLUMBING
J 2
(-7725 5150);
DISPLAY 0.872340 (-7725 5150);
PAINT GREEN (-7725 5150);
DISPLAY INVISIBLE (-7725 5150);
FORCEPROP 1 LAST HDL_TAP TRUE
J 2
(-8050 4975);
DISPLAY 0.872340 (-8050 4975);
DISPLAY INVISIBLE (-8050 4975);
FORCEPROP 1 LAST PATH I88
J 2
(-7723 5100);
DISPLAY 0.872340 (-7723 5100);
PAINT GREEN (-7723 5100);
DISPLAY INVISIBLE (-7723 5100);
FORCEADD TAP..1
R 2
(-7725 5150);
FORCEPROP 3 LASTPIN (-7675 5150) SIG_NAME M_H_CPU0_SA_CA<2>
J 0
(-7665 5160);
DISPLAY 0.659574 (-7665 5160);
PAINT MONO (-7665 5160);
DISPLAY INVISIBLE (-7665 5160);
FORCEPROP 1 LASTPIN (-7675 5150) BN 2
J 2
(-7663 5158);
DISPLAY 0.489362 (-7663 5158);
PAINT GREEN (-7663 5158);
FORCEPROP 2 LAST CDS_LIB mstr_standard
J 0
(-7725 5150);
DISPLAY 0.723404 (-7725 5150);
PAINT MONO (-7725 5150);
DISPLAY INVISIBLE (-7725 5150);
FORCEPROP 1 LAST BODY_TYPE PLUMBING
J 2
(-7725 5200);
DISPLAY 0.872340 (-7725 5200);
PAINT GREEN (-7725 5200);
DISPLAY INVISIBLE (-7725 5200);
FORCEPROP 1 LAST HDL_TAP TRUE
J 2
(-8050 5025);
DISPLAY 0.872340 (-8050 5025);
DISPLAY INVISIBLE (-8050 5025);
FORCEPROP 1 LAST PATH I89
J 2
(-7723 5150);
DISPLAY 0.872340 (-7723 5150);
PAINT GREEN (-7723 5150);
DISPLAY INVISIBLE (-7723 5150);
FORCEADD OFFPAGE..1
(-8175 3050);
FORCEPROP 2 LAST $XR0 17 
J 0
(-8396 3050);
DISPLAY 0.638298 (-8396 3050);
PAINT MONO (-8396 3050);
FORCEPROP 2 LAST CDS_LIB mstr_standard
J 0
(-8175 3050);
DISPLAY 0.808511 (-8175 3050);
DISPLAY INVISIBLE (-8175 3050);
FORCEPROP 1 LAST OFFPAGE TRUE
J 0
(-7850 2925);
DISPLAY 0.872340 (-7850 2925);
PAINT GREEN (-7850 2925);
DISPLAY INVISIBLE (-7850 2925);
FORCEPROP 1 LAST COMMENT_BODY TRUE
J 0
(-8050 2950);
DISPLAY 0.872340 (-8050 2950);
PAINT GREEN (-8050 2950);
DISPLAY INVISIBLE (-8050 2950);
FORCEPROP 2 LAST PATH I9
J 0
(-8600 3100);
DISPLAY 1.021277 (-8600 3100);
DISPLAY INVISIBLE (-8600 3100);
FORCEADD TAP..1
R 2
(-7725 5200);
FORCEPROP 3 LASTPIN (-7675 5200) SIG_NAME M_H_CPU0_SA_CA<3>
J 0
(-7665 5210);
DISPLAY 0.659574 (-7665 5210);
PAINT MONO (-7665 5210);
DISPLAY INVISIBLE (-7665 5210);
FORCEPROP 1 LASTPIN (-7675 5200) BN 3
J 2
(-7663 5208);
DISPLAY 0.489362 (-7663 5208);
PAINT GREEN (-7663 5208);
FORCEPROP 2 LAST CDS_LIB mstr_standard
J 0
(-7725 5200);
DISPLAY 0.723404 (-7725 5200);
PAINT MONO (-7725 5200);
DISPLAY INVISIBLE (-7725 5200);
FORCEPROP 1 LAST BODY_TYPE PLUMBING
J 2
(-7725 5250);
DISPLAY 0.872340 (-7725 5250);
PAINT GREEN (-7725 5250);
DISPLAY INVISIBLE (-7725 5250);
FORCEPROP 1 LAST HDL_TAP TRUE
J 2
(-8050 5075);
DISPLAY 0.872340 (-8050 5075);
DISPLAY INVISIBLE (-8050 5075);
FORCEPROP 1 LAST PATH I90
J 2
(-7723 5200);
DISPLAY 0.872340 (-7723 5200);
PAINT GREEN (-7723 5200);
DISPLAY INVISIBLE (-7723 5200);
FORCEADD TAP..1
R 2
(-7725 5250);
FORCEPROP 3 LASTPIN (-7675 5250) SIG_NAME M_H_CPU0_SA_CA<4>
J 0
(-7665 5260);
DISPLAY 0.659574 (-7665 5260);
PAINT MONO (-7665 5260);
DISPLAY INVISIBLE (-7665 5260);
FORCEPROP 1 LASTPIN (-7675 5250) BN 4
J 2
(-7663 5258);
DISPLAY 0.489362 (-7663 5258);
PAINT GREEN (-7663 5258);
FORCEPROP 2 LAST CDS_LIB mstr_standard
J 0
(-7725 5250);
DISPLAY 0.723404 (-7725 5250);
PAINT MONO (-7725 5250);
DISPLAY INVISIBLE (-7725 5250);
FORCEPROP 1 LAST BODY_TYPE PLUMBING
J 2
(-7725 5300);
DISPLAY 0.872340 (-7725 5300);
PAINT GREEN (-7725 5300);
DISPLAY INVISIBLE (-7725 5300);
FORCEPROP 1 LAST HDL_TAP TRUE
J 2
(-8050 5125);
DISPLAY 0.872340 (-8050 5125);
DISPLAY INVISIBLE (-8050 5125);
FORCEPROP 1 LAST PATH I91
J 2
(-7723 5250);
DISPLAY 0.872340 (-7723 5250);
PAINT GREEN (-7723 5250);
DISPLAY INVISIBLE (-7723 5250);
FORCEADD TAP..1
R 2
(-7725 5300);
FORCEPROP 3 LASTPIN (-7675 5300) SIG_NAME M_H_CPU0_SA_CA<5>
J 0
(-7665 5310);
DISPLAY 0.659574 (-7665 5310);
PAINT MONO (-7665 5310);
DISPLAY INVISIBLE (-7665 5310);
FORCEPROP 1 LASTPIN (-7675 5300) BN 5
J 2
(-7663 5308);
DISPLAY 0.489362 (-7663 5308);
PAINT GREEN (-7663 5308);
FORCEPROP 2 LAST CDS_LIB mstr_standard
J 0
(-7725 5300);
DISPLAY 0.723404 (-7725 5300);
PAINT MONO (-7725 5300);
DISPLAY INVISIBLE (-7725 5300);
FORCEPROP 1 LAST BODY_TYPE PLUMBING
J 2
(-7725 5350);
DISPLAY 0.872340 (-7725 5350);
PAINT GREEN (-7725 5350);
DISPLAY INVISIBLE (-7725 5350);
FORCEPROP 1 LAST HDL_TAP TRUE
J 2
(-8050 5175);
DISPLAY 0.872340 (-8050 5175);
DISPLAY INVISIBLE (-8050 5175);
FORCEPROP 1 LAST PATH I92
J 2
(-7723 5300);
DISPLAY 0.872340 (-7723 5300);
PAINT GREEN (-7723 5300);
DISPLAY INVISIBLE (-7723 5300);
FORCEADD TAP..1
R 2
(-7725 5350);
FORCEPROP 3 LASTPIN (-7675 5350) SIG_NAME M_H_CPU0_SA_CA<6>
J 0
(-7665 5360);
DISPLAY 0.659574 (-7665 5360);
PAINT MONO (-7665 5360);
DISPLAY INVISIBLE (-7665 5360);
FORCEPROP 1 LASTPIN (-7675 5350) BN 6
J 2
(-7663 5358);
DISPLAY 0.489362 (-7663 5358);
PAINT GREEN (-7663 5358);
FORCEPROP 2 LAST CDS_LIB mstr_standard
J 0
(-7725 5350);
DISPLAY 0.723404 (-7725 5350);
PAINT MONO (-7725 5350);
DISPLAY INVISIBLE (-7725 5350);
FORCEPROP 1 LAST BODY_TYPE PLUMBING
J 2
(-7725 5400);
DISPLAY 0.872340 (-7725 5400);
PAINT GREEN (-7725 5400);
DISPLAY INVISIBLE (-7725 5400);
FORCEPROP 1 LAST HDL_TAP TRUE
J 2
(-8050 5225);
DISPLAY 0.872340 (-8050 5225);
DISPLAY INVISIBLE (-8050 5225);
FORCEPROP 1 LAST PATH I93
J 2
(-7723 5350);
DISPLAY 0.872340 (-7723 5350);
PAINT GREEN (-7723 5350);
DISPLAY INVISIBLE (-7723 5350);
FORCEADD TAP..1
(-6025 3800);
FORCEPROP 3 LASTPIN (-6075 3800) SIG_NAME M_H_CPU0_SA_DQ<0>
J 0
(-6065 3810);
DISPLAY 0.659574 (-6065 3810);
PAINT MONO (-6065 3810);
DISPLAY INVISIBLE (-6065 3810);
FORCEPROP 1 LASTPIN (-6075 3800) BN 0
J 0
(-6087 3808);
DISPLAY 0.489362 (-6087 3808);
PAINT GREEN (-6087 3808);
FORCEPROP 2 LAST CDS_LIB mstr_standard
J 0
(-6025 3800);
DISPLAY 0.723404 (-6025 3800);
PAINT MONO (-6025 3800);
DISPLAY INVISIBLE (-6025 3800);
FORCEPROP 1 LAST BODY_TYPE PLUMBING
J 0
(-6025 3850);
DISPLAY 0.872340 (-6025 3850);
PAINT GREEN (-6025 3850);
DISPLAY INVISIBLE (-6025 3850);
FORCEPROP 1 LAST HDL_TAP TRUE
J 0
(-5700 3675);
DISPLAY 0.872340 (-5700 3675);
DISPLAY INVISIBLE (-5700 3675);
FORCEPROP 1 LAST PATH I94
J 0
(-6027 3800);
DISPLAY 0.872340 (-6027 3800);
PAINT GREEN (-6027 3800);
DISPLAY INVISIBLE (-6027 3800);
FORCEADD TAP..1
(-6025 3850);
FORCEPROP 3 LASTPIN (-6075 3850) SIG_NAME M_H_CPU0_SA_DQ<1>
J 0
(-6065 3860);
DISPLAY 0.659574 (-6065 3860);
PAINT MONO (-6065 3860);
DISPLAY INVISIBLE (-6065 3860);
FORCEPROP 1 LASTPIN (-6075 3850) BN 1
J 0
(-6087 3858);
DISPLAY 0.489362 (-6087 3858);
PAINT GREEN (-6087 3858);
FORCEPROP 2 LAST CDS_LIB mstr_standard
J 0
(-6025 3850);
DISPLAY 0.723404 (-6025 3850);
PAINT MONO (-6025 3850);
DISPLAY INVISIBLE (-6025 3850);
FORCEPROP 1 LAST BODY_TYPE PLUMBING
J 0
(-6025 3900);
DISPLAY 0.872340 (-6025 3900);
PAINT GREEN (-6025 3900);
DISPLAY INVISIBLE (-6025 3900);
FORCEPROP 1 LAST HDL_TAP TRUE
J 0
(-5700 3725);
DISPLAY 0.872340 (-5700 3725);
DISPLAY INVISIBLE (-5700 3725);
FORCEPROP 1 LAST PATH I95
J 0
(-6027 3850);
DISPLAY 0.872340 (-6027 3850);
PAINT GREEN (-6027 3850);
DISPLAY INVISIBLE (-6027 3850);
FORCEADD TAP..1
(-6025 3900);
FORCEPROP 3 LASTPIN (-6075 3900) SIG_NAME M_H_CPU0_SA_DQ<2>
J 0
(-6065 3910);
DISPLAY 0.659574 (-6065 3910);
PAINT MONO (-6065 3910);
DISPLAY INVISIBLE (-6065 3910);
FORCEPROP 1 LASTPIN (-6075 3900) BN 2
J 0
(-6087 3908);
DISPLAY 0.489362 (-6087 3908);
PAINT GREEN (-6087 3908);
FORCEPROP 2 LAST CDS_LIB mstr_standard
J 0
(-6025 3900);
DISPLAY 0.723404 (-6025 3900);
PAINT MONO (-6025 3900);
DISPLAY INVISIBLE (-6025 3900);
FORCEPROP 1 LAST BODY_TYPE PLUMBING
J 0
(-6025 3950);
DISPLAY 0.872340 (-6025 3950);
PAINT GREEN (-6025 3950);
DISPLAY INVISIBLE (-6025 3950);
FORCEPROP 1 LAST HDL_TAP TRUE
J 0
(-5700 3775);
DISPLAY 0.872340 (-5700 3775);
DISPLAY INVISIBLE (-5700 3775);
FORCEPROP 1 LAST PATH I96
J 0
(-6027 3900);
DISPLAY 0.872340 (-6027 3900);
PAINT GREEN (-6027 3900);
DISPLAY INVISIBLE (-6027 3900);
FORCEADD TAP..1
(-6025 3950);
FORCEPROP 3 LASTPIN (-6075 3950) SIG_NAME M_H_CPU0_SA_DQ<3>
J 0
(-6065 3960);
DISPLAY 0.659574 (-6065 3960);
PAINT MONO (-6065 3960);
DISPLAY INVISIBLE (-6065 3960);
FORCEPROP 1 LASTPIN (-6075 3950) BN 3
J 0
(-6087 3958);
DISPLAY 0.489362 (-6087 3958);
PAINT GREEN (-6087 3958);
FORCEPROP 2 LAST CDS_LIB mstr_standard
J 0
(-6025 3950);
DISPLAY 0.723404 (-6025 3950);
PAINT MONO (-6025 3950);
DISPLAY INVISIBLE (-6025 3950);
FORCEPROP 1 LAST BODY_TYPE PLUMBING
J 0
(-6025 4000);
DISPLAY 0.872340 (-6025 4000);
PAINT GREEN (-6025 4000);
DISPLAY INVISIBLE (-6025 4000);
FORCEPROP 1 LAST HDL_TAP TRUE
J 0
(-5700 3825);
DISPLAY 0.872340 (-5700 3825);
DISPLAY INVISIBLE (-5700 3825);
FORCEPROP 1 LAST PATH I97
J 0
(-6027 3950);
DISPLAY 0.872340 (-6027 3950);
PAINT GREEN (-6027 3950);
DISPLAY INVISIBLE (-6027 3950);
FORCEADD TAP..1
(-6025 4000);
FORCEPROP 3 LASTPIN (-6075 4000) SIG_NAME M_H_CPU0_SA_DQ<4>
J 0
(-6065 4010);
DISPLAY 0.659574 (-6065 4010);
PAINT MONO (-6065 4010);
DISPLAY INVISIBLE (-6065 4010);
FORCEPROP 1 LASTPIN (-6075 4000) BN 4
J 0
(-6087 4008);
DISPLAY 0.489362 (-6087 4008);
PAINT GREEN (-6087 4008);
FORCEPROP 2 LAST CDS_LIB mstr_standard
J 0
(-6025 4000);
DISPLAY 0.723404 (-6025 4000);
PAINT MONO (-6025 4000);
DISPLAY INVISIBLE (-6025 4000);
FORCEPROP 1 LAST BODY_TYPE PLUMBING
J 0
(-6025 4050);
DISPLAY 0.872340 (-6025 4050);
PAINT GREEN (-6025 4050);
DISPLAY INVISIBLE (-6025 4050);
FORCEPROP 1 LAST HDL_TAP TRUE
J 0
(-5700 3875);
DISPLAY 0.872340 (-5700 3875);
DISPLAY INVISIBLE (-5700 3875);
FORCEPROP 1 LAST PATH I98
J 0
(-6027 4000);
DISPLAY 0.872340 (-6027 4000);
PAINT GREEN (-6027 4000);
DISPLAY INVISIBLE (-6027 4000);
FORCEADD TAP..1
(-6025 4050);
FORCEPROP 3 LASTPIN (-6075 4050) SIG_NAME M_H_CPU0_SA_DQ<5>
J 0
(-6065 4060);
DISPLAY 0.659574 (-6065 4060);
PAINT MONO (-6065 4060);
DISPLAY INVISIBLE (-6065 4060);
FORCEPROP 1 LASTPIN (-6075 4050) BN 5
J 0
(-6087 4058);
DISPLAY 0.489362 (-6087 4058);
PAINT GREEN (-6087 4058);
FORCEPROP 2 LAST CDS_LIB mstr_standard
J 0
(-6025 4050);
DISPLAY 0.723404 (-6025 4050);
PAINT MONO (-6025 4050);
DISPLAY INVISIBLE (-6025 4050);
FORCEPROP 1 LAST BODY_TYPE PLUMBING
J 0
(-6025 4100);
DISPLAY 0.872340 (-6025 4100);
PAINT GREEN (-6025 4100);
DISPLAY INVISIBLE (-6025 4100);
FORCEPROP 1 LAST HDL_TAP TRUE
J 0
(-5700 3925);
DISPLAY 0.872340 (-5700 3925);
DISPLAY INVISIBLE (-5700 3925);
FORCEPROP 1 LAST PATH I99
J 0
(-6027 4050);
DISPLAY 0.872340 (-6027 4050);
PAINT GREEN (-6027 4050);
DISPLAY INVISIBLE (-6027 4050);
FORCEADD DNS..2
(-8375 2250);
PAINT RED (-8375 2250);
FORCEPROP 2 LAST CDS_LIB mstr_misc
J 0
(-8375 2250);
DISPLAY INVISIBLE (-8375 2250);
FORCEPROP 1 LAST COMMENT_BODY TRUE
R 1
J 0
(-8300 2025);
DISPLAY 0.872340 (-8300 2025);
PAINT PEACH (-8300 2025);
DISPLAY INVISIBLE (-8300 2025);
FORCEADD QUANTA_TITLE_BLOCK_C..1
(0 0);
FORCEPROP 0 LAST CDS_CON_LAST_MODIFIED Thu Sep 14 16:12:08 2023
J 0
(-1885 15);
DISPLAY INVISIBLE (-1885 15);
FORCEPROP 1 LAST CUSTOM_TXT_CDS <CON_LAST_MODIFIED>
J 0
(-1885 15);
DISPLAY 0.978723 (-1885 15);
FORCEPROP 2 LAST CUSTOM_TXT_CDS <XR_PAGE_TITLE>
J 0
(-7890 5250);
DISPLAY 0.638298 (-7890 5250);
PAINT PINK (-7890 5250);
DISPLAY INVISIBLE (-7890 5250);
FORCEPROP 1 LAST CUSTOM_TXT_CDS <NAME_2>
J 0
(-3175 50);
FORCEPROP 1 LAST CUSTOM_TXT_CDS <NAME_1>
J 0
(-3175 175);
FORCEPROP 1 LAST CUSTOM_TXT_CDS <Q_NUMBER>
J 0
(-1403 103);
DISPLAY 1.212766 (-1403 103);
FORCEPROP 1 LAST CUSTOM_TXT_CDS <Q_PROJ>
J 0
(-2382 102);
DISPLAY 1.212766 (-2382 102);
FORCEPROP 1 LAST CUSTOM_TXT_CDS <Q_REV>
J 0
(-184 103);
DISPLAY 1.212766 (-184 103);
FORCEPROP 1 LAST CUSTOM_TXT_CDS <CON_PAGE_NUM> OF <CON_TOTAL_PAGES>
J 0
(-446 18);
DISPLAY 0.978723 (-446 18);
FORCEPROP 1 LAST Q_TITLE DDR5 - CPU0 CHH
J 0
(-9275 75);
DISPLAY 2.446809 (-9275 75);
PAINT GREEN (-9275 75);
FORCEPROP 2 LAST CDS_LIB pure_quanta
J 0
(0 0);
DISPLAY INVISIBLE (0 0);
FORCEPROP 1 LAST CDS_LMAN_SYM_OUTLINE -9475,6775,100,-125
J 0
(0 0);
DISPLAY 0.468085 (0 0);
PAINT GREEN (0 0);
DISPLAY INVISIBLE (0 0);
FORCEPROP 2 LAST PAGE_BORDER TRUE
J 0
(-7890 5250);
DISPLAY 0.638298 (-7890 5250);
PAINT PINK (-7890 5250);
DISPLAY INVISIBLE (-7890 5250);
FORCEPROP 2 LAST CDS_XR_PAGE_TITLE CR-93 : @T6G_MB_LIB.T6G(SCH_1):PAGE93
J 0
(-7890 5250);
DISPLAY 0.638298 (-7890 5250);
PAINT PINK (-7890 5250);
DISPLAY INVISIBLE (-7890 5250);
FORCEPROP 1 LAST Q_DEPT BU9
J 1
(-3763 49);
DISPLAY 1.957447 (-3763 49);
PAINT GREEN (-3763 49);
DISPLAY INVISIBLE (-3763 49);
FORCEPROP 1 LAST COMMENT_BODY TRUE
J 0
(12 -13);
DISPLAY 0.978723 (12 -13);
PAINT GREEN (12 -13);
DISPLAY INVISIBLE (12 -13);
WIRE 17 -1 (-7775 3425)(-7775 3475);
WIRE 17 -1 (-7775 3425)(-7775 3375);
WIRE 17 -1 (-7775 3525)(-7775 3475);
WIRE 17 -1 (-7775 3525)(-7775 3550);
WIRE 17 -1 (-7775 3325)(-7775 3375);
WIRE 17 -1 (-7775 3275)(-7775 3325);
WIRE 17 -1 (-7775 3550)(-8275 3550);
FORCEPROP 2 LAST SIG_NAME M_H_CPU0_SB_CB<7:0>
J 0
(-8225 3560);
DISPLAY 0.489362 (-8225 3560);
WIRE 17 -1 (-5975 4425)(-5975 4375);
WIRE 17 -1 (-5975 4425)(-5975 4475);
WIRE 17 -1 (-5975 4375)(-5975 4325);
WIRE 17 -1 (-5975 4325)(-5975 4275);
WIRE 17 -1 (-5975 4475)(-5975 4525);
WIRE 17 -1 (-5975 4525)(-5975 4575);
WIRE 17 -1 (-5975 4275)(-5975 4225);
WIRE 17 -1 (-5975 4225)(-5975 4175);
WIRE 17 -1 (-5975 4575)(-5975 4625);
WIRE 17 -1 (-5975 4675)(-5975 4625);
WIRE 17 -1 (-5975 4175)(-5975 4125);
WIRE 17 -1 (-5975 4125)(-5975 4075);
WIRE 17 -1 (-5975 4725)(-5975 4675);
WIRE 17 -1 (-5975 4775)(-5975 4725);
WIRE 17 -1 (-5975 4075)(-5975 4025);
WIRE 17 -1 (-5975 3975)(-5975 4025);
WIRE 17 -1 (-5975 4825)(-5975 4775);
WIRE 17 -1 (-5975 4875)(-5975 4825);
WIRE 17 -1 (-5975 3925)(-5975 3975);
WIRE 17 -1 (-5975 3875)(-5975 3925);
WIRE 17 -1 (-5975 4925)(-5975 4875);
WIRE 17 -1 (-5975 4975)(-5975 4925);
WIRE 17 -1 (-5975 3825)(-5975 3875);
WIRE 17 -1 (-5975 5025)(-5975 4975);
WIRE 17 -1 (-5975 5075)(-5975 5025);
WIRE 17 -1 (-5975 5125)(-5975 5075);
WIRE 17 -1 (-5975 5175)(-5975 5125);
WIRE 17 -1 (-5975 5225)(-5975 5175);
WIRE 17 -1 (-5975 5275)(-5975 5225);
WIRE 17 -1 (-5975 5325)(-5975 5275);
WIRE 17 -1 (-5975 5375)(-5975 5325);
WIRE 17 -1 (-5975 5400)(-5975 5375);
WIRE 17 -1 (-5975 5400)(-5400 5400);
FORCEPROP 2 LAST SIG_NAME M_H_CPU0_SA_DQ<31:0>
J 0
(-5910 5410);
DISPLAY 0.489362 (-5910 5410);
WIRE 17 -1 (-7775 5375)(-7775 5400);
WIRE 17 -1 (-7775 5325)(-7775 5375);
WIRE 17 -1 (-7775 5400)(-8275 5400);
FORCEPROP 2 LAST SIG_NAME M_H_CPU0_SA_CA<6:0>
J 0
(-8260 5410);
DISPLAY 0.489362 (-8260 5410);
WIRE 17 -1 (-7775 5275)(-7775 5325);
WIRE 17 -1 (-7775 5225)(-7775 5275);
WIRE 17 -1 (-7775 5175)(-7775 5225);
WIRE 17 -1 (-7775 5125)(-7775 5175);
WIRE 17 -1 (-3450 3350)(-3450 3325);
WIRE 17 -1 (-3450 3350)(-2550 3350);
FORCEPROP 2 LAST SIG_NAME M_H_CPU0_SB_DQS_DP<9:0>
J 0
(-3185 3360);
DISPLAY 0.489362 (-3185 3360);
WIRE 17 -1 (-3250 3300)(-3250 3275);
WIRE 17 -1 (-3250 3300)(-2550 3300);
FORCEPROP 2 LAST SIG_NAME M_H_CPU0_SB_DQS_DN<9:0>
J 0
(-3185 3310);
DISPLAY 0.489362 (-3185 3310);
WIRE 17 -1 (-3450 4400)(-3450 4375);
WIRE 17 -1 (-3450 4400)(-2550 4400);
FORCEPROP 2 LAST SIG_NAME M_H_CPU0_SA_DQS_DP<9:0>
J 0
(-3185 4410);
DISPLAY 0.489362 (-3185 4410);
WIRE 17 -1 (-3250 4350)(-3250 4325);
WIRE 17 -1 (-3250 4350)(-2550 4350);
FORCEPROP 2 LAST SIG_NAME M_H_CPU0_SA_DQS_DN<9:0>
J 0
(-3185 4360);
DISPLAY 0.489362 (-3185 4360);
WIRE 17 -1 (-3450 4375)(-3450 4275);
WIRE 17 -1 (-3450 4275)(-3450 4175);
WIRE 17 -1 (-3450 4175)(-3450 4075);
WIRE 17 -1 (-3250 4325)(-3250 4225);
WIRE 17 -1 (-3250 4225)(-3250 4125);
WIRE 17 -1 (-3250 4125)(-3250 4025);
WIRE 17 -1 (-3250 3175)(-3250 3075);
WIRE 17 -1 (-3250 3275)(-3250 3175);
WIRE 17 -1 (-3250 3075)(-3250 2975);
WIRE 17 -1 (-3250 2975)(-3250 2875);
WIRE 17 -1 (-3450 4075)(-3450 3975);
WIRE 17 -1 (-3450 3125)(-3450 3025);
WIRE 17 -1 (-3450 3225)(-3450 3125);
WIRE 17 -1 (-3450 3025)(-3450 2925);
WIRE 17 -1 (-3450 2825)(-3450 2925);
WIRE 17 -1 (-3450 3325)(-3450 3225);
WIRE 17 -1 (-3450 2725)(-3450 2825);
WIRE 17 -1 (-3450 2625)(-3450 2725);
WIRE 17 -1 (-3250 2775)(-3250 2875);
WIRE 17 -1 (-3250 2675)(-3250 2775);
WIRE 17 -1 (-3250 2575)(-3250 2675);
WIRE 17 -1 (-3250 4025)(-3250 3925);
WIRE 17 -1 (-3250 3825)(-3250 3925);
WIRE 17 -1 (-3250 3725)(-3250 3825);
WIRE 17 -1 (-3250 3625)(-3250 3725);
WIRE 17 -1 (-3450 2625)(-3450 2525);
WIRE 17 -1 (-3250 2575)(-3250 2475);
WIRE 17 -1 (-3450 3875)(-3450 3975);
WIRE 17 -1 (-3450 3775)(-3450 3875);
WIRE 17 -1 (-3450 3675)(-3450 3775);
WIRE 17 -1 (-3450 3675)(-3450 3575);
WIRE 17 -1 (-3250 3625)(-3250 3525);
WIRE 17 -1 (-3450 2525)(-3450 2425);
WIRE 17 -1 (-3250 2475)(-3250 2375);
WIRE 17 -1 (-3450 3575)(-3450 3475);
WIRE 17 -1 (-3250 3525)(-3250 3425);
WIRE 17 -1 (-5975 2175)(-5975 2225);
WIRE 17 -1 (-5975 2225)(-5975 2275);
WIRE 17 -1 (-5975 2275)(-5975 2325);
WIRE 17 -1 (-5975 2325)(-5975 2375);
WIRE 17 -1 (-5975 2425)(-5975 2375);
WIRE 17 -1 (-5975 2475)(-5975 2425);
WIRE 17 -1 (-5975 2525)(-5975 2475);
WIRE 17 -1 (-5975 2575)(-5975 2525);
WIRE 17 -1 (-5975 2625)(-5975 2575);
WIRE 17 -1 (-5975 2675)(-5975 2625);
WIRE 17 -1 (-5975 2725)(-5975 2675);
WIRE 17 -1 (-5975 2775)(-5975 2725);
WIRE 17 -1 (-5975 2775)(-5975 2825);
WIRE 17 -1 (-5975 2825)(-5975 2875);
WIRE 17 -1 (-5975 2875)(-5975 2925);
WIRE 17 -1 (-5975 2925)(-5975 2975);
WIRE 17 -1 (-5975 3025)(-5975 2975);
WIRE 17 -1 (-5975 3075)(-5975 3025);
WIRE 17 -1 (-5975 3125)(-5975 3075);
WIRE 17 -1 (-5975 3175)(-5975 3125);
WIRE 17 -1 (-5975 3225)(-5975 3175);
WIRE 17 -1 (-5975 3275)(-5975 3225);
WIRE 17 -1 (-5975 3325)(-5975 3275);
WIRE 17 -1 (-5975 3375)(-5975 3325);
WIRE 17 -1 (-5975 3425)(-5975 3375);
WIRE 17 -1 (-5975 3475)(-5975 3425);
WIRE 17 -1 (-5975 3525)(-5975 3475);
WIRE 17 -1 (-5975 3575)(-5975 3525);
WIRE 17 -1 (-5975 3625)(-5975 3575);
WIRE 17 -1 (-5975 3675)(-5975 3625);
WIRE 17 -1 (-5975 3725)(-5975 3675);
WIRE 17 -1 (-5975 3750)(-5975 3725);
WIRE 17 -1 (-5975 3750)(-5400 3750);
FORCEPROP 2 LAST SIG_NAME M_H_CPU0_SB_DQ<31:0>
J 0
(-5910 3760);
DISPLAY 0.489362 (-5910 3760);
WIRE 17 -1 (-7775 3175)(-7775 3225);
WIRE 17 -1 (-7775 3225)(-7775 3275);
WIRE 17 -1 (-7775 3625)(-7775 3675);
WIRE 17 -1 (-7775 3675)(-7775 3725);
WIRE 17 -1 (-7775 3725)(-7775 3775);
WIRE 17 -1 (-7775 3775)(-7775 3825);
WIRE 17 -1 (-7775 3875)(-7775 3825);
WIRE 17 -1 (-7775 3875)(-7775 3925);
WIRE 17 -1 (-7775 3975)(-7775 3925);
WIRE 17 -1 (-7775 3975)(-7775 4000);
WIRE 17 -1 (-7775 4000)(-8275 4000);
FORCEPROP 2 LAST SIG_NAME M_H_CPU0_SA_CB<7:0>
J 0
(-8225 4010);
DISPLAY 0.489362 (-8225 4010);
WIRE 17 -1 (-7775 4975)(-7775 5000);
WIRE 17 -1 (-7775 4925)(-7775 4975);
WIRE 17 -1 (-7775 5000)(-8275 5000);
FORCEPROP 2 LAST SIG_NAME M_H_CPU0_SB_CA<6:0>
J 0
(-8260 5010);
DISPLAY 0.489362 (-8260 5010);
WIRE 17 -1 (-7775 4875)(-7775 4925);
WIRE 17 -1 (-7775 4825)(-7775 4875);
WIRE 17 -1 (-7775 4775)(-7775 4825);
WIRE 17 -1 (-7775 4725)(-7775 4775);
WIRE 17 -1 (-7775 4675)(-7775 4725);
WIRE 17 -1 (-7775 5075)(-7775 5125);
WIRE 16 -1 (-6425 925)(-6425 1075);
WIRE 16 -1 (-8650 3000)(-8650 3075);
WIRE 16 -1 (-8400 2350)(-8400 2375);
WIRE 16 -1 (-7475 3250)(-7675 3250);
WIRE 16 -1 (-7475 3000)(-8125 3000);
FORCEPROP 2 LAST SIG_NAME M_H_CPU0_ALERT_N
J 0
(-8110 3010);
DISPLAY 0.489362 (-8110 3010);
WIRE 16 -1 (-8275 2800)(-8250 2800);
WIRE 16 -1 (-8275 2725)(-8275 2800);
WIRE 16 -1 (-8275 2725)(-8775 2725);
FORCEPROP 2 LAST SIG_NAME I3C_SPD_DDRGL_CPU0_SDA
J 0
(-8785 2735);
DISPLAY 0.489362 (-8785 2735);
WIRE 16 -1 (-7575 2575)(-7650 2575);
WIRE 16 -1 (-7575 2750)(-7575 2575);
WIRE 16 -1 (-7475 2750)(-7575 2750);
FORCEPROP 2 LAST SIG_NAME I3C_SPD_DDRH_CPU0_SCL
J 0
(-7960 2760);
DISPLAY 0.446809 (-7960 2760);
FORCEPROP 2 LASTPROP $XRERR UNIQUE?
J 0
(-8200 2760);
DISPLAY 0.638298 (-8200 2760);
PAINT MONO (-8200 2760);
DISPLAY INVISIBLE (-8200 2760);
WIRE 16 -1 (-7475 2800)(-8050 2800);
FORCEPROP 2 LAST SIG_NAME I3C_SPD_DDRH_CPU0_SDA
J 0
(-7960 2810);
DISPLAY 0.446809 (-7960 2810);
FORCEPROP 2 LASTPROP $XRERR UNIQUE?
J 0
(-8200 2810);
DISPLAY 0.638298 (-8200 2810);
PAINT MONO (-8200 2810);
DISPLAY INVISIBLE (-8200 2810);
WIRE 16 -1 (-7850 2575)(-8375 2575);
FORCEPROP 2 LAST SIG_NAME I3C_SPD_DDRGL_CPU0_SCL
J 0
(-8385 2585);
DISPLAY 0.489362 (-8385 2585);
WIRE 16 -1 (-7475 2850)(-8425 2850);
FORCEPROP 2 LAST SIG_NAME PD_CHH_CPU0_DIMM_SAA
J 0
(-8400 2860);
DISPLAY 0.489362 (-8400 2860);
WIRE 16 -1 (-8650 3275)(-8650 3300);
WIRE 16 -1 (-8650 3300)(-8550 3300);
WIRE 16 -1 (-8550 3325)(-8550 3300);
WIRE 16 -1 (-8550 3300)(-8550 2900);
WIRE 16 -1 (-8550 2900)(-7475 2900);
WIRE 16 -1 (-7475 2500)(-8200 2500);
FORCEPROP 2 LAST SIG_NAME PWRGD_CHH_CPU0_DIMM
J 0
(-8110 2510);
DISPLAY 0.489362 (-8110 2510);
FORCEPROP 2 LASTPROP $XRERR UNIQUE?
J 0
(-8350 2510);
DISPLAY 0.638298 (-8350 2510);
PAINT MONO (-8350 2510);
DISPLAY INVISIBLE (-8350 2510);
WIRE 16 -1 (-8200 2500)(-8200 2100);
WIRE 16 -1 (-8200 2100)(-8400 2100);
WIRE 16 -1 (-8400 2100)(-8425 2100);
WIRE 16 -1 (-8400 2150)(-8400 2100);
WIRE 16 -1 (-7475 1900)(-8275 1900);
FORCEPROP 2 LAST SIG_NAME M_H_CPU0_SB_RSP<0>
J 0
(-8225 1910);
DISPLAY 0.489362 (-8225 1910);
WIRE 16 -1 (-7475 1950)(-8275 1950);
FORCEPROP 2 LAST SIG_NAME M_H_CPU0_SA_RSP<0>
J 0
(-8225 1960);
DISPLAY 0.489362 (-8225 1960);
WIRE 16 -1 (-6075 4650)(-6275 4650);
WIRE 16 -1 (-6425 1350)(-6425 1275);
WIRE 16 -1 (-6425 1350)(-7150 1350);
FORCEPROP 2 LAST SIG_NAME PD_CHH_CPU0_DIMM_SAA
J 0
(-7135 1360);
DISPLAY 0.489362 (-7135 1360);
WIRE 16 -1 (-7475 3950)(-7675 3950);
WIRE 16 -1 (-7475 3800)(-7675 3800);
WIRE 16 -1 (-7475 3650)(-7675 3650);
WIRE 16 -1 (-7475 3500)(-7675 3500);
WIRE 16 -1 (-7475 5050)(-7675 5050);
WIRE 16 -1 (-7475 4650)(-7675 4650);
WIRE 16 -1 (-7475 5100)(-7675 5100);
WIRE 16 -1 (-7475 4700)(-7675 4700);
WIRE 16 -1 (-7475 5150)(-7675 5150);
WIRE 16 -1 (-7475 4750)(-7675 4750);
WIRE 16 -1 (-7475 5200)(-7675 5200);
WIRE 16 -1 (-7475 4800)(-7675 4800);
WIRE 16 -1 (-7475 4850)(-7675 4850);
WIRE 16 -1 (-7475 4900)(-7675 4900);
WIRE 16 -1 (-7475 4950)(-7675 4950);
WIRE 16 -1 (-7475 3900)(-7675 3900);
WIRE 16 -1 (-7475 3850)(-7675 3850);
WIRE 16 -1 (-7475 3750)(-7675 3750);
WIRE 16 -1 (-7475 3700)(-7675 3700);
WIRE 16 -1 (-7475 3600)(-7675 3600);
WIRE 16 -1 (-7475 3450)(-7675 3450);
WIRE 16 -1 (-7475 3350)(-7675 3350);
WIRE 16 -1 (-7475 3300)(-7675 3300);
WIRE 16 -1 (-7475 3200)(-7675 3200);
WIRE 16 -1 (-7475 3150)(-7675 3150);
WIRE 16 -1 (-7475 4050)(-8275 4050);
FORCEPROP 2 LAST SIG_NAME M_H_CPU0_CLK_DN<0>
J 0
(-8225 4060);
DISPLAY 0.489362 (-8225 4060);
WIRE 16 -1 (-7475 4100)(-8275 4100);
FORCEPROP 2 LAST SIG_NAME M_H_CPU0_CLK_DP<0>
J 0
(-8225 4110);
DISPLAY 0.489362 (-8225 4110);
WIRE 16 -1 (-7475 4350)(-8275 4350);
FORCEPROP 2 LAST SIG_NAME M_H_CPU0_SA_CS_N<0>
J 0
(-8225 4360);
DISPLAY 0.489362 (-8225 4360);
WIRE 16 -1 (-7475 4200)(-8275 4200);
FORCEPROP 2 LAST SIG_NAME M_H_CPU0_SB_CS_N<0>
J 0
(-8225 4210);
DISPLAY 0.489362 (-8225 4210);
WIRE 16 -1 (-7475 4400)(-8275 4400);
FORCEPROP 2 LAST SIG_NAME M_H_CPU0_SA_CS_N<1>
J 0
(-8225 4410);
DISPLAY 0.489362 (-8225 4410);
WIRE 16 -1 (-7475 4250)(-8275 4250);
FORCEPROP 2 LAST SIG_NAME M_H_CPU0_SB_CS_N<1>
J 0
(-8225 4260);
DISPLAY 0.489362 (-8225 4260);
WIRE 16 -1 (-6075 5300)(-6275 5300);
WIRE 16 -1 (-6075 5250)(-6275 5250);
WIRE 16 -1 (-6075 5200)(-6275 5200);
WIRE 16 -1 (-6275 5150)(-6075 5150);
WIRE 16 -1 (-6075 5100)(-6275 5100);
WIRE 16 -1 (-6075 5050)(-6275 5050);
WIRE 16 -1 (-6075 5000)(-6275 5000);
WIRE 16 -1 (-6275 4950)(-6075 4950);
WIRE 16 -1 (-6075 4900)(-6275 4900);
WIRE 16 -1 (-6075 4850)(-6275 4850);
WIRE 16 -1 (-6075 4800)(-6275 4800);
WIRE 16 -1 (-6275 4750)(-6075 4750);
WIRE 16 -1 (-6075 4700)(-6275 4700);
WIRE 16 -1 (-6075 4600)(-6275 4600);
WIRE 16 -1 (-6275 4550)(-6075 4550);
WIRE 16 -1 (-6075 4500)(-6275 4500);
WIRE 16 -1 (-6075 4450)(-6275 4450);
WIRE 16 -1 (-6275 4350)(-6075 4350);
WIRE 16 -1 (-6075 4300)(-6275 4300);
WIRE 16 -1 (-6075 4250)(-6275 4250);
WIRE 16 -1 (-6075 4200)(-6275 4200);
WIRE 16 -1 (-6275 4150)(-6075 4150);
WIRE 16 -1 (-6075 4100)(-6275 4100);
WIRE 16 -1 (-6075 4050)(-6275 4050);
WIRE 16 -1 (-6075 4000)(-6275 4000);
WIRE 16 -1 (-6275 3950)(-6075 3950);
WIRE 16 -1 (-6075 3900)(-6275 3900);
WIRE 16 -1 (-6075 3850)(-6275 3850);
WIRE 16 -1 (-6075 3800)(-6275 3800);
WIRE 16 -1 (-6275 3700)(-6075 3700);
WIRE 16 -1 (-6075 3650)(-6275 3650);
WIRE 16 -1 (-6075 3600)(-6275 3600);
WIRE 16 -1 (-6075 3550)(-6275 3550);
WIRE 16 -1 (-6275 3500)(-6075 3500);
WIRE 16 -1 (-6075 3450)(-6275 3450);
WIRE 16 -1 (-6075 3400)(-6275 3400);
WIRE 16 -1 (-6075 3350)(-6275 3350);
WIRE 16 -1 (-6275 3300)(-6075 3300);
WIRE 16 -1 (-6075 3250)(-6275 3250);
WIRE 16 -1 (-6075 3200)(-6275 3200);
WIRE 16 -1 (-6075 3150)(-6275 3150);
WIRE 16 -1 (-6275 3100)(-6075 3100);
WIRE 16 -1 (-6075 3050)(-6275 3050);
WIRE 16 -1 (-6075 3000)(-6275 3000);
WIRE 16 -1 (-6075 2950)(-6275 2950);
WIRE 16 -1 (-6275 2900)(-6075 2900);
WIRE 16 -1 (-6075 2850)(-6275 2850);
WIRE 16 -1 (-6075 2800)(-6275 2800);
WIRE 16 -1 (-6075 2750)(-6275 2750);
WIRE 16 -1 (-6275 2700)(-6075 2700);
WIRE 16 -1 (-6075 2650)(-6275 2650);
WIRE 16 -1 (-6075 2600)(-6275 2600);
WIRE 16 -1 (-6075 2550)(-6275 2550);
WIRE 16 -1 (-6275 2500)(-6075 2500);
WIRE 16 -1 (-6075 2450)(-6275 2450);
WIRE 16 -1 (-6075 2400)(-6275 2400);
WIRE 16 -1 (-6075 2350)(-6275 2350);
WIRE 16 -1 (-6275 2300)(-6075 2300);
WIRE 16 -1 (-6075 2250)(-6275 2250);
WIRE 16 -1 (-6075 2200)(-6275 2200);
WIRE 16 -1 (-6075 2150)(-6275 2150);
WIRE 16 -1 (-7475 4550)(-8275 4550);
FORCEPROP 2 LAST SIG_NAME M_H_CPU0_SA_PAR
J 0
(-8225 4560);
DISPLAY 0.489362 (-8225 4560);
WIRE 16 -1 (-7475 4500)(-8275 4500);
FORCEPROP 2 LAST SIG_NAME M_H_CPU0_SB_PAR
J 0
(-8225 4510);
DISPLAY 0.489362 (-8225 4510);
WIRE 16 -1 (-6275 5350)(-6075 5350);
WIRE 16 -1 (-3700 4100)(-3350 4100);
WIRE 16 -1 (-3550 4050)(-3700 4050);
WIRE 16 -1 (-3550 3200)(-3700 3200);
WIRE 16 -1 (-3700 3150)(-3350 3150);
WIRE 16 -1 (-3550 3100)(-3700 3100);
WIRE 16 -1 (-3700 3400)(-3350 3400);
WIRE 16 -1 (-3550 3450)(-3700 3450);
WIRE 16 -1 (-3700 2350)(-3350 2350);
WIRE 16 -1 (-3550 2400)(-3700 2400);
WIRE 16 -1 (-3700 3500)(-3350 3500);
WIRE 16 -1 (-3700 3550)(-3550 3550);
WIRE 16 -1 (-3700 2450)(-3350 2450);
WIRE 16 -1 (-3700 2500)(-3550 2500);
WIRE 16 -1 (-3700 3600)(-3350 3600);
WIRE 16 -1 (-3550 3650)(-3700 3650);
WIRE 16 -1 (-3700 2550)(-3350 2550);
WIRE 16 -1 (-3550 2600)(-3700 2600);
WIRE 16 -1 (-3700 3700)(-3350 3700);
WIRE 16 -1 (-3550 3750)(-3700 3750);
WIRE 16 -1 (-3700 2650)(-3350 2650);
WIRE 16 -1 (-3550 2700)(-3700 2700);
WIRE 16 -1 (-3700 3800)(-3350 3800);
WIRE 16 -1 (-3550 3850)(-3700 3850);
WIRE 16 -1 (-3700 2750)(-3350 2750);
WIRE 16 -1 (-3550 2800)(-3700 2800);
WIRE 16 -1 (-3700 3900)(-3350 3900);
WIRE 16 -1 (-3700 3950)(-3550 3950);
WIRE 16 -1 (-3700 2850)(-3350 2850);
WIRE 16 -1 (-3700 2900)(-3550 2900);
WIRE 16 -1 (-3700 4000)(-3350 4000);
WIRE 16 -1 (-3350 2950)(-3700 2950);
WIRE 16 -1 (-3550 3000)(-3700 3000);
WIRE 16 -1 (-3550 4150)(-3700 4150);
WIRE 16 -1 (-3700 3050)(-3350 3050);
WIRE 16 -1 (-3700 4200)(-3350 4200);
WIRE 16 -1 (-3550 4250)(-3700 4250);
WIRE 16 -1 (-3700 4300)(-3350 4300);
WIRE 16 -1 (-3700 4350)(-3550 4350);
WIRE 16 -1 (-3700 3250)(-3350 3250);
WIRE 16 -1 (-3700 3300)(-3550 3300);
WIRE 16 -1 (-7475 5250)(-7675 5250);
WIRE 16 -1 (-7475 5300)(-7675 5300);
WIRE 16 -1 (-7475 5350)(-7675 5350);
WIRE 16 -1 (-6075 4400)(-6275 4400);
WIRE 16 -1 (-7475 3400)(-7675 3400);
WIRE 16 -1 (-7475 3050)(-8125 3050);
FORCEPROP 2 LAST SIG_NAME M_H_CPU0_RESET_N
J 0
(-8110 3060);
DISPLAY 0.489362 (-8110 3060);
WIRE 16 -1 (-2325 6200)(-2200 6200);
WIRE 16 -1 (-2325 6200)(-2900 6200);
WIRE 16 -1 (-2325 6200)(-2325 6100);
WIRE 16 -1 (-2200 5300)(-2200 6200);
WIRE 16 -1 (-1900 5300)(-2200 5300);
WIRE 16 -1 (-2200 5250)(-2200 5300);
WIRE 16 -1 (-2900 6100)(-2900 6200);
WIRE 16 -1 (-2900 6200)(-2900 6275);
WIRE 16 -1 (-1900 5250)(-2200 5250);
WIRE 16 -1 (-2200 5250)(-2200 5200);
WIRE 16 -1 (-2200 5200)(-1900 5200);
WIRE 16 -1 (-2325 5775)(-2325 5900);
WIRE 16 -1 (-2325 5775)(-2900 5775);
WIRE 16 -1 (-2900 5775)(-2900 5900);
WIRE 16 -1 (-2900 5775)(-2900 5700);
WIRE 16 -1 (-400 2150)(-400 2050);
WIRE 16 -1 (-400 2200)(-400 2150);
WIRE 16 -1 (-400 2150)(-700 2150);
WIRE 16 -1 (-400 2050)(-700 2050);
WIRE 16 -1 (-400 2050)(-400 2000);
WIRE 16 -1 (-400 2000)(-400 1950);
WIRE 16 -1 (-400 2000)(-700 2000);
WIRE 16 -1 (-400 2250)(-400 2200);
WIRE 16 -1 (-400 2200)(-700 2200);
WIRE 16 -1 (-400 2300)(-400 2250);
WIRE 16 -1 (-400 2250)(-700 2250);
WIRE 16 -1 (-400 1950)(-400 1700);
WIRE 16 -1 (-400 1950)(-700 1950);
WIRE 16 -1 (-400 2350)(-400 2300);
WIRE 16 -1 (-400 2300)(-700 2300);
WIRE 16 -1 (-400 2400)(-400 2350);
WIRE 16 -1 (-400 2350)(-700 2350);
WIRE 16 -1 (-400 2450)(-400 2400);
WIRE 16 -1 (-400 2400)(-700 2400);
WIRE 16 -1 (-400 2500)(-400 2450);
WIRE 16 -1 (-400 2450)(-700 2450);
WIRE 16 -1 (-400 2550)(-400 2500);
WIRE 16 -1 (-400 2500)(-700 2500);
WIRE 16 -1 (-400 2600)(-400 2550);
WIRE 16 -1 (-400 2550)(-700 2550);
WIRE 16 -1 (-400 2650)(-400 2600);
WIRE 16 -1 (-400 2600)(-700 2600);
WIRE 16 -1 (-400 2700)(-400 2650);
WIRE 16 -1 (-400 2650)(-700 2650);
WIRE 16 -1 (-400 2750)(-400 2700);
WIRE 16 -1 (-400 2700)(-700 2700);
WIRE 16 -1 (-400 2800)(-400 2750);
WIRE 16 -1 (-400 2750)(-700 2750);
WIRE 16 -1 (-400 2850)(-400 2800);
WIRE 16 -1 (-400 2800)(-700 2800);
WIRE 16 -1 (-400 2900)(-400 2850);
WIRE 16 -1 (-400 2850)(-700 2850);
WIRE 16 -1 (-400 2950)(-400 2900);
WIRE 16 -1 (-400 2900)(-700 2900);
WIRE 16 -1 (-400 3000)(-400 2950);
WIRE 16 -1 (-400 2950)(-700 2950);
WIRE 16 -1 (-400 3050)(-400 3000);
WIRE 16 -1 (-400 3000)(-700 3000);
WIRE 16 -1 (-400 3100)(-400 3050);
WIRE 16 -1 (-400 3050)(-700 3050);
WIRE 16 -1 (-400 3150)(-400 3100);
WIRE 16 -1 (-400 3100)(-700 3100);
WIRE 16 -1 (-400 3200)(-400 3150);
WIRE 16 -1 (-400 3150)(-700 3150);
WIRE 16 -1 (-400 3250)(-400 3200);
WIRE 16 -1 (-400 3200)(-700 3200);
WIRE 16 -1 (-400 3300)(-400 3250);
WIRE 16 -1 (-400 3250)(-700 3250);
WIRE 16 -1 (-400 3350)(-400 3300);
WIRE 16 -1 (-400 3300)(-700 3300);
WIRE 16 -1 (-400 3400)(-400 3350);
WIRE 16 -1 (-400 3350)(-700 3350);
WIRE 16 -1 (-400 3450)(-400 3400);
WIRE 16 -1 (-400 3400)(-700 3400);
WIRE 16 -1 (-400 3500)(-400 3450);
WIRE 16 -1 (-400 3450)(-700 3450);
WIRE 16 -1 (-400 3550)(-400 3500);
WIRE 16 -1 (-400 3500)(-700 3500);
WIRE 16 -1 (-400 3600)(-400 3550);
WIRE 16 -1 (-400 3550)(-700 3550);
WIRE 16 -1 (-400 3650)(-400 3600);
WIRE 16 -1 (-400 3600)(-700 3600);
WIRE 16 -1 (-400 3700)(-400 3650);
WIRE 16 -1 (-400 3650)(-700 3650);
WIRE 16 -1 (-400 3750)(-400 3700);
WIRE 16 -1 (-400 3700)(-700 3700);
WIRE 16 -1 (-400 3800)(-400 3750);
WIRE 16 -1 (-400 3750)(-700 3750);
WIRE 16 -1 (-400 3850)(-400 3800);
WIRE 16 -1 (-400 3800)(-700 3800);
WIRE 16 -1 (-400 3900)(-400 3850);
WIRE 16 -1 (-400 3850)(-700 3850);
WIRE 16 -1 (-400 3950)(-400 3900);
WIRE 16 -1 (-400 3900)(-700 3900);
WIRE 16 -1 (-400 4000)(-400 3950);
WIRE 16 -1 (-400 3950)(-700 3950);
WIRE 16 -1 (-400 4050)(-400 4000);
WIRE 16 -1 (-400 4000)(-700 4000);
WIRE 16 -1 (-400 4100)(-400 4050);
WIRE 16 -1 (-400 4050)(-700 4050);
WIRE 16 -1 (-400 4150)(-400 4100);
WIRE 16 -1 (-400 4100)(-700 4100);
WIRE 16 -1 (-400 4200)(-400 4150);
WIRE 16 -1 (-400 4150)(-700 4150);
WIRE 16 -1 (-400 4250)(-400 4200);
WIRE 16 -1 (-400 4200)(-700 4200);
WIRE 16 -1 (-400 4300)(-400 4250);
WIRE 16 -1 (-400 4250)(-700 4250);
WIRE 16 -1 (-400 4350)(-400 4300);
WIRE 16 -1 (-400 4300)(-700 4300);
WIRE 16 -1 (-400 4400)(-400 4350);
WIRE 16 -1 (-400 4350)(-700 4350);
WIRE 16 -1 (-400 4450)(-400 4400);
WIRE 16 -1 (-400 4400)(-700 4400);
WIRE 16 -1 (-400 4500)(-400 4450);
WIRE 16 -1 (-400 4450)(-700 4450);
WIRE 16 -1 (-400 4550)(-400 4500);
WIRE 16 -1 (-400 4500)(-700 4500);
WIRE 16 -1 (-400 4600)(-400 4550);
WIRE 16 -1 (-400 4550)(-700 4550);
WIRE 16 -1 (-400 4650)(-400 4600);
WIRE 16 -1 (-400 4600)(-700 4600);
WIRE 16 -1 (-400 4700)(-400 4650);
WIRE 16 -1 (-400 4650)(-700 4650);
WIRE 16 -1 (-400 4750)(-400 4700);
WIRE 16 -1 (-400 4700)(-700 4700);
WIRE 16 -1 (-400 4800)(-400 4750);
WIRE 16 -1 (-400 4750)(-700 4750);
WIRE 16 -1 (-400 4850)(-400 4800);
WIRE 16 -1 (-400 4800)(-700 4800);
WIRE 16 -1 (-400 4900)(-400 4850);
WIRE 16 -1 (-400 4850)(-700 4850);
WIRE 16 -1 (-400 4950)(-400 4900);
WIRE 16 -1 (-400 4900)(-700 4900);
WIRE 16 -1 (-400 5000)(-400 4950);
WIRE 16 -1 (-400 4950)(-700 4950);
WIRE 16 -1 (-400 5050)(-400 5000);
WIRE 16 -1 (-400 5000)(-700 5000);
WIRE 16 -1 (-400 5100)(-400 5050);
WIRE 16 -1 (-400 5050)(-700 5050);
WIRE 16 -1 (-400 5150)(-400 5100);
WIRE 16 -1 (-400 5100)(-700 5100);
WIRE 16 -1 (-400 5200)(-400 5150);
WIRE 16 -1 (-400 5150)(-700 5150);
WIRE 16 -1 (-400 5250)(-400 5200);
WIRE 16 -1 (-400 5200)(-700 5200);
WIRE 16 -1 (-400 5300)(-400 5250);
WIRE 16 -1 (-400 5250)(-700 5250);
WIRE 16 -1 (-400 5300)(-700 5300);
WIRE 16 -1 (-1900 2100)(-2200 2100);
WIRE 16 -1 (-2200 2150)(-2200 2100);
WIRE 16 -1 (-2200 2100)(-2200 2050);
WIRE 16 -1 (-1900 2050)(-2200 2050);
WIRE 16 -1 (-2200 2050)(-2200 1925);
WIRE 16 -1 (-1900 2150)(-2200 2150);
WIRE 16 -1 (-2200 2200)(-2200 2150);
WIRE 16 -1 (-1900 2200)(-2200 2200);
WIRE 16 -1 (-2200 2250)(-2200 2200);
WIRE 16 -1 (-1900 2250)(-2200 2250);
WIRE 16 -1 (-2200 2300)(-2200 2250);
WIRE 16 -1 (-1900 2300)(-2200 2300);
WIRE 16 -1 (-2200 2350)(-2200 2300);
WIRE 16 -1 (-1900 2350)(-2200 2350);
WIRE 16 -1 (-2200 2400)(-2200 2350);
WIRE 16 -1 (-1900 2400)(-2200 2400);
WIRE 16 -1 (-2200 2450)(-2200 2400);
WIRE 16 -1 (-1900 2450)(-2200 2450);
WIRE 16 -1 (-2200 2500)(-2200 2450);
WIRE 16 -1 (-1900 2500)(-2200 2500);
WIRE 16 -1 (-2200 2550)(-2200 2500);
WIRE 16 -1 (-1900 2550)(-2200 2550);
WIRE 16 -1 (-2200 2600)(-2200 2550);
WIRE 16 -1 (-1900 2600)(-2200 2600);
WIRE 16 -1 (-2200 2650)(-2200 2600);
WIRE 16 -1 (-1900 2650)(-2200 2650);
WIRE 16 -1 (-2200 2700)(-2200 2650);
WIRE 16 -1 (-1900 2700)(-2200 2700);
WIRE 16 -1 (-2200 2750)(-2200 2700);
WIRE 16 -1 (-1900 2750)(-2200 2750);
WIRE 16 -1 (-2200 2800)(-2200 2750);
WIRE 16 -1 (-1900 2800)(-2200 2800);
WIRE 16 -1 (-2200 2850)(-2200 2800);
WIRE 16 -1 (-1900 2850)(-2200 2850);
WIRE 16 -1 (-2200 2900)(-2200 2850);
WIRE 16 -1 (-1900 2900)(-2200 2900);
WIRE 16 -1 (-2200 2950)(-2200 2900);
WIRE 16 -1 (-1900 2950)(-2200 2950);
WIRE 16 -1 (-2200 3000)(-2200 2950);
WIRE 16 -1 (-1900 3000)(-2200 3000);
WIRE 16 -1 (-2200 3050)(-2200 3000);
WIRE 16 -1 (-1900 3050)(-2200 3050);
WIRE 16 -1 (-2200 3100)(-2200 3050);
WIRE 16 -1 (-1900 3100)(-2200 3100);
WIRE 16 -1 (-2200 3150)(-2200 3100);
WIRE 16 -1 (-1900 3150)(-2200 3150);
WIRE 16 -1 (-2200 3200)(-2200 3150);
WIRE 16 -1 (-1900 3200)(-2200 3200);
WIRE 16 -1 (-2200 3250)(-2200 3200);
WIRE 16 -1 (-1900 3250)(-2200 3250);
WIRE 16 -1 (-2200 3300)(-2200 3250);
WIRE 16 -1 (-1900 3300)(-2200 3300);
WIRE 16 -1 (-2200 3350)(-2200 3300);
WIRE 16 -1 (-1900 3350)(-2200 3350);
WIRE 16 -1 (-2200 3400)(-2200 3350);
WIRE 16 -1 (-1900 3400)(-2200 3400);
WIRE 16 -1 (-2200 3450)(-2200 3400);
WIRE 16 -1 (-1900 3450)(-2200 3450);
WIRE 16 -1 (-2200 3500)(-2200 3450);
WIRE 16 -1 (-1900 3500)(-2200 3500);
WIRE 16 -1 (-2200 3550)(-2200 3500);
WIRE 16 -1 (-1900 3550)(-2200 3550);
WIRE 16 -1 (-2200 3600)(-2200 3550);
WIRE 16 -1 (-1900 3600)(-2200 3600);
WIRE 16 -1 (-2200 3650)(-2200 3600);
WIRE 16 -1 (-1900 3650)(-2200 3650);
WIRE 16 -1 (-2200 3700)(-2200 3650);
WIRE 16 -1 (-1900 3700)(-2200 3700);
WIRE 16 -1 (-2200 3750)(-2200 3700);
WIRE 16 -1 (-1900 3750)(-2200 3750);
WIRE 16 -1 (-2200 3800)(-2200 3750);
WIRE 16 -1 (-1900 3800)(-2200 3800);
WIRE 16 -1 (-2200 3850)(-2200 3800);
WIRE 16 -1 (-1900 3850)(-2200 3850);
WIRE 16 -1 (-2200 3900)(-2200 3850);
WIRE 16 -1 (-1900 3900)(-2200 3900);
WIRE 16 -1 (-2200 3950)(-2200 3900);
WIRE 16 -1 (-1900 3950)(-2200 3950);
WIRE 16 -1 (-2200 4000)(-2200 3950);
WIRE 16 -1 (-1900 4000)(-2200 4000);
WIRE 16 -1 (-2200 4050)(-2200 4000);
WIRE 16 -1 (-2200 4100)(-2200 4050);
WIRE 16 -1 (-1900 4050)(-2200 4050);
WIRE 16 -1 (-1900 4100)(-2200 4100);
WIRE 16 -1 (-2200 4150)(-2200 4100);
WIRE 16 -1 (-1900 4150)(-2200 4150);
WIRE 16 -1 (-2200 4200)(-2200 4150);
WIRE 16 -1 (-1900 4200)(-2200 4200);
WIRE 16 -1 (-2200 4250)(-2200 4200);
WIRE 16 -1 (-1900 4250)(-2200 4250);
WIRE 16 -1 (-2200 4300)(-2200 4250);
WIRE 16 -1 (-1900 4300)(-2200 4300);
WIRE 16 -1 (-2200 4350)(-2200 4300);
WIRE 16 -1 (-1900 4350)(-2200 4350);
WIRE 16 -1 (-2200 4400)(-2200 4350);
WIRE 16 -1 (-1900 4400)(-2200 4400);
WIRE 16 -1 (-2200 4450)(-2200 4400);
WIRE 16 -1 (-1900 4450)(-2200 4450);
WIRE 16 -1 (-2200 4500)(-2200 4450);
WIRE 16 -1 (-1900 4500)(-2200 4500);
WIRE 16 -1 (-2200 4550)(-2200 4500);
WIRE 16 -1 (-1900 4550)(-2200 4550);
WIRE 16 -1 (-2200 4600)(-2200 4550);
WIRE 16 -1 (-1900 4600)(-2200 4600);
WIRE 16 -1 (-2200 4650)(-2200 4600);
WIRE 16 -1 (-1900 4650)(-2200 4650);
WIRE 16 -1 (-2200 4700)(-2200 4650);
WIRE 16 -1 (-1900 4700)(-2200 4700);
WIRE 16 -1 (-2200 4750)(-2200 4700);
WIRE 16 -1 (-1900 4750)(-2200 4750);
WIRE 16 -1 (-2200 4800)(-2200 4750);
WIRE 16 -1 (-1900 4800)(-2200 4800);
WIRE 16 -1 (-2200 4850)(-2200 4800);
WIRE 16 -1 (-1900 4850)(-2200 4850);
WIRE 16 -1 (-2200 4900)(-2200 4850);
WIRE 16 -1 (-1900 4900)(-2200 4900);
WIRE 16 -1 (-2200 4950)(-2200 4900);
WIRE 16 -1 (-1900 4950)(-2200 4950);
WIRE 16 -1 (-2200 5000)(-2200 4950);
WIRE 16 -1 (-1900 5000)(-2200 5000);
WIRE 16 -1 (-2200 5050)(-2200 5000);
WIRE 16 -1 (-1900 5050)(-2200 5050);
WIRE 16 -1 (-2200 5100)(-2200 5050);
WIRE 16 -1 (-1900 5100)(-2200 5100);
WIRE 16 -1 (-2200 5150)(-2200 5100);
WIRE 16 -1 (-1900 5150)(-2200 5150);
WIRE 16 -1 (-9025 2100)(-8625 2100);
FORCEPROP 2 LAST SIG_NAME PWRGD_CHGL_CPU0
J 0
(-9010 2110);
DISPLAY 0.489362 (-9010 2110);
DOT 1 (-2900 6200);
DOT 1 (-2325 6200);
DOT 1 (-2900 5775);
DOT 1 (-400 5050);
DOT 1 (-400 4950);
DOT 1 (-8400 2100);
DOT 1 (-8550 3300);
DOT 1 (-2200 2050);
DOT 1 (-2200 2200);
DOT 1 (-2200 2150);
DOT 1 (-2200 2100);
DOT 1 (-2200 2300);
DOT 1 (-2200 2250);
DOT 1 (-2200 2450);
DOT 1 (-2200 2400);
DOT 1 (-2200 2350);
DOT 1 (-2200 2550);
DOT 1 (-2200 2500);
DOT 1 (-2200 2600);
DOT 1 (-2200 2750);
DOT 1 (-2200 2700);
DOT 1 (-2200 2650);
DOT 1 (-2200 2800);
DOT 1 (-2200 3000);
DOT 1 (-2200 2900);
DOT 1 (-2200 3050);
DOT 1 (-2200 3100);
DOT 1 (-2200 2950);
DOT 1 (-2200 3200);
DOT 1 (-2200 3250);
DOT 1 (-2200 3150);
DOT 1 (-2200 3350);
DOT 1 (-2200 3300);
DOT 1 (-2200 3450);
DOT 1 (-2200 3500);
DOT 1 (-2200 3400);
DOT 1 (-2200 3600);
DOT 1 (-2200 3550);
DOT 1 (-2200 3700);
DOT 1 (-2200 3750);
DOT 1 (-2200 3650);
DOT 1 (-2200 3850);
DOT 1 (-2200 3800);
DOT 1 (-400 2050);
DOT 1 (-400 1950);
DOT 1 (-400 2000);
DOT 1 (-400 2300);
DOT 1 (-400 2250);
DOT 1 (-400 2200);
DOT 1 (-400 2150);
DOT 1 (-400 2450);
DOT 1 (-400 2400);
DOT 1 (-400 2350);
DOT 1 (-400 2550);
DOT 1 (-400 2500);
DOT 1 (-400 2600);
DOT 1 (-400 2750);
DOT 1 (-400 2700);
DOT 1 (-400 2650);
DOT 1 (-400 2800);
DOT 1 (-400 2850);
DOT 1 (-400 3000);
DOT 1 (-400 2900);
DOT 1 (-400 3050);
DOT 1 (-400 3100);
DOT 1 (-400 2950);
DOT 1 (-400 3200);
DOT 1 (-400 3250);
DOT 1 (-400 3150);
DOT 1 (-400 3350);
DOT 1 (-400 3300);
DOT 1 (-400 3500);
DOT 1 (-400 3450);
DOT 1 (-400 3400);
DOT 1 (-400 3600);
DOT 1 (-400 3550);
DOT 1 (-400 3750);
DOT 1 (-400 3700);
DOT 1 (-400 3650);
DOT 1 (-400 3850);
DOT 1 (-400 3800);
DOT 1 (-2200 4000);
DOT 1 (-2200 3950);
DOT 1 (-2200 3900);
DOT 1 (-2200 4100);
DOT 1 (-2200 4050);
DOT 1 (-2200 4250);
DOT 1 (-2200 4150);
DOT 1 (-2200 4300);
DOT 1 (-2200 4450);
DOT 1 (-2200 4500);
DOT 1 (-2200 4400);
DOT 1 (-2200 4600);
DOT 1 (-2200 4550);
DOT 1 (-2200 4650);
DOT 1 (-2200 4800);
DOT 1 (-2200 4750);
DOT 1 (-2200 4700);
DOT 1 (-2200 4850);
DOT 1 (-2200 4900);
DOT 1 (-2200 5000);
DOT 1 (-2200 4950);
DOT 1 (-2200 5100);
DOT 1 (-2200 5050);
DOT 1 (-2200 5250);
DOT 1 (-2200 5300);
DOT 1 (-400 4000);
DOT 1 (-400 3950);
DOT 1 (-400 3900);
DOT 1 (-400 4100);
DOT 1 (-400 4050);
DOT 1 (-400 4250);
DOT 1 (-400 4200);
DOT 1 (-400 4150);
DOT 1 (-400 4350);
DOT 1 (-400 4300);
DOT 1 (-400 4450);
DOT 1 (-400 4500);
DOT 1 (-400 4400);
DOT 1 (-400 4600);
DOT 1 (-400 4550);
DOT 1 (-400 4650);
DOT 1 (-400 4750);
DOT 1 (-400 4700);
DOT 1 (-400 4850);
DOT 1 (-400 4900);
DOT 1 (-400 5000);
DOT 1 (-400 5100);
DOT 1 (-400 5150);
DOT 1 (-400 5200);
DOT 1 (-400 5250);
DOT 1 (-2200 2850);
DOT 1 (-2200 4350);
DOT 1 (-400 4800);
DOT 1 (-2200 4200);
QUIT
